G04 ================== begin FILE IDENTIFICATION RECORD ==================*
G04 Layout Name:  t6m_pdb_d_0928_1400_274.brd*
G04 Film Name:    gnd1*
G04 File Format:  Gerber RS274X*
G04 File Origin:  Cadence Allegro 16.3-S048*
G04 Origin Date:  Tue Nov 26 11:01:52 2013*
G04 *
G04 Layer:  DRAWING FORMAT/TITLE_BLOCK*
G04 Layer:  VIA CLASS/GND1*
G04 Layer:  PIN/GND1*
G04 Layer:  MANUFACTURING/PHOTOPLOT_OUTLINE*
G04 Layer:  ETCH/GND1*
G04 Layer:  DRAWING FORMAT/TITLE_DATA_GND1*
G04 *
G04 Offset:    (0.00 0.00)*
G04 Mirror:    No*
G04 Mode:      Negative*
G04 Rotation:  0*
G04 FullContactRelief:  No*
G04 UndefLineWidth:     6.00*
G04 ================== end FILE IDENTIFICATION RECORD ====================*
%FSLAX25Y25*MOIN*%
%IR0*IPPOS*OFA0.00000B0.00000*MIA0B0*SFA1.00000B1.00000*%
%ADD26C,.03*%
%ADD34C,.04*%
%ADD38C,.05*%
%ADD17C,.06*%
%AMMACRO27*
4,1,36,0.0,.01,
-.001736,.009848,
-.00342,.009397,
-.005,.00866,
-.006428,.00766,
-.00766,.006428,
-.00866,.005,
-.009397,.00342,
-.009848,.001736,
-.01,0.0,
-.009848,-.001736,
-.009397,-.00342,
-.00866,-.005,
-.00766,-.006428,
-.006428,-.00766,
-.005,-.00866,
-.00342,-.009397,
-.001736,-.009848,
0.0,-.01,
.001736,-.009848,
.00342,-.009397,
.005,-.00866,
.006428,-.00766,
.00766,-.006428,
.00866,-.005,
.009397,-.00342,
.009848,-.001736,
.01,0.0,
.009848,.001736,
.009397,.00342,
.00866,.005,
.00766,.006428,
.006428,.00766,
.005,.00866,
.00342,.009397,
.001736,.009848,
0.0,.01,
0.0*
%
%ADD27MACRO27*%
%ADD29C,.064*%
%ADD13C,.056*%
%ADD18C,.048*%
%AMMACRO39*
4,1,36,0.0,.004,
.000695,.003939,
.001368,.003759,
.002,.003464,
.002571,.003064,
.003064,.002571,
.003464,.002,
.003759,.001368,
.003939,.000695,
.004,0.0,
.003939,-.000695,
.003759,-.001368,
.003464,-.002,
.003064,-.002571,
.002571,-.003064,
.002,-.003464,
.001368,-.003759,
.000695,-.003939,
0.0,-.004,
-.000695,-.003939,
-.001368,-.003759,
-.002,-.003464,
-.002571,-.003064,
-.003064,-.002571,
-.003464,-.002,
-.003759,-.001368,
-.003939,-.000695,
-.004,0.0,
-.003939,.000695,
-.003759,.001368,
-.003464,.002,
-.003064,.002571,
-.002571,.003064,
-.002,.003464,
-.001368,.003759,
-.000695,.003939,
0.0,.004,
180.*
%
%ADD39MACRO39*%
%AMMACRO33*
4,1,36,0.0,.009,
.001563,.008863,
.003078,.008457,
.0045,.007794,
.005785,.006894,
.006894,.005785,
.007794,.0045,
.008457,.003078,
.008863,.001563,
.009,0.0,
.008863,-.001563,
.008457,-.003078,
.007794,-.0045,
.006894,-.005785,
.005785,-.006894,
.0045,-.007794,
.003078,-.008457,
.001563,-.008863,
0.0,-.009,
-.001563,-.008863,
-.003078,-.008457,
-.0045,-.007794,
-.005785,-.006894,
-.006894,-.005785,
-.007794,-.0045,
-.008457,-.003078,
-.008863,-.001563,
-.009,0.0,
-.008863,.001563,
-.008457,.003078,
-.007794,.0045,
-.006894,.005785,
-.005785,.006894,
-.0045,.007794,
-.003078,.008457,
-.001563,.008863,
0.0,.009,
90.*
%
%ADD33MACRO33*%
%ADD22C,.077*%
%ADD10C,.059*%
%AMMACRO35*
4,1,36,0.0,.009,
.001563,.008863,
.003078,.008457,
.0045,.007794,
.005785,.006894,
.006894,.005785,
.007794,.0045,
.008457,.003078,
.008863,.001563,
.009,0.0,
.008863,-.001563,
.008457,-.003078,
.007794,-.0045,
.006894,-.005785,
.005785,-.006894,
.0045,-.007794,
.003078,-.008457,
.001563,-.008863,
0.0,-.009,
-.001563,-.008863,
-.003078,-.008457,
-.0045,-.007794,
-.005785,-.006894,
-.006894,-.005785,
-.007794,-.0045,
-.008457,-.003078,
-.008863,-.001563,
-.009,0.0,
-.008863,.001563,
-.008457,.003078,
-.007794,.0045,
-.006894,.005785,
-.005785,.006894,
-.0045,.007794,
-.003078,.008457,
-.001563,.008863,
0.0,.009,
0.0*
%
%ADD35MACRO35*%
%AMMACRO16*
4,1,15,.02438,.01377,
.026401,.009327,
.027619,.004601,
.027999,-.000265,
.027527,-.005123,
.02622,-.009825,
.02438,-.01377,
.02948,-.01887,
.032309,-.013464,
.034156,-.007649,
.034965,-.001602,
.034712,.004494,
.033405,.010454,
.031082,.016095,
.02948,.01887,
.02438,.01377,
90.*
4,1,15,.01377,-.02438,
.009327,-.026401,
.004601,-.027619,
-.000265,-.027999,
-.005123,-.027527,
-.009825,-.02622,
-.01377,-.02438,
-.01887,-.02948,
-.013464,-.032309,
-.007649,-.034156,
-.001602,-.034965,
.004494,-.034712,
.010454,-.033405,
.016095,-.031082,
.01887,-.02948,
.01377,-.02438,
90.*
4,1,15,-.02438,-.01377,
-.026401,-.009327,
-.027619,-.004601,
-.027999,.000265,
-.027527,.005123,
-.02622,.009825,
-.02438,.01377,
-.02948,.01887,
-.032309,.013464,
-.034156,.007649,
-.034965,.001602,
-.034712,-.004494,
-.033405,-.010454,
-.031082,-.016095,
-.02948,-.01887,
-.02438,-.01377,
90.*
4,1,15,-.01377,.02438,
-.009327,.026401,
-.004601,.027619,
.000265,.027999,
.005123,.027527,
.009825,.02622,
.01377,.02438,
.01887,.02948,
.013464,.032309,
.007649,.034156,
.001602,.034965,
-.004494,.034712,
-.010454,.033405,
-.016095,.031082,
-.01887,.02948,
-.01377,.02438,
90.*
%
%ADD16MACRO16*%
%AMMACRO25*
4,1,15,.02401,.0134,
.025972,.009027,
.027145,.00438,
.027493,-.0004,
.027006,-.005168,
.025698,-.009779,
.02401,-.0134,
.02912,-.01851,
.031892,-.013172,
.033695,-.007434,
.034474,-.00147,
.034205,.004538,
.032897,.010409,
.03059,.015964,
.02912,.01851,
.02401,.0134,
0.0*
4,1,15,.0134,-.02401,
.009027,-.025972,
.00438,-.027145,
-.0004,-.027493,
-.005168,-.027006,
-.009779,-.025698,
-.0134,-.02401,
-.01851,-.02912,
-.013172,-.031892,
-.007434,-.033695,
-.00147,-.034474,
.004538,-.034205,
.010409,-.032897,
.015964,-.03059,
.01851,-.02912,
.0134,-.02401,
0.0*
4,1,15,-.02401,-.0134,
-.025972,-.009027,
-.027145,-.00438,
-.027493,.0004,
-.027006,.005168,
-.025698,.009779,
-.02401,.0134,
-.02912,.01851,
-.031892,.013172,
-.033695,.007434,
-.034474,.00147,
-.034205,-.004538,
-.032897,-.010409,
-.03059,-.015964,
-.02912,-.01851,
-.02401,-.0134,
0.0*
4,1,15,-.0134,.02401,
-.009027,.025972,
-.00438,.027145,
.0004,.027493,
.005168,.027006,
.009779,.025698,
.0134,.02401,
.01851,.02912,
.013172,.031892,
.007434,.033695,
.00147,.034474,
-.004538,.034205,
-.010409,.032897,
-.015964,.03059,
-.01851,.02912,
-.0134,.02401,
0.0*
%
%ADD25MACRO25*%
%AMMACRO21*
4,1,17,.03273,.02212,
.036074,.0161,
.038322,.009592,
.039405,.002791,
.039291,-.004094,
.037983,-.010854,
.035521,-.017285,
.03273,-.02212,
.03775,-.02715,
.041891,-.020182,
.044759,-.012601,
.046267,-.004638,
.04637,.003467,
.045063,.011466,
.042388,.019117,
.038424,.026188,
.03775,.02715,
.03273,.02212,
0.0*
4,1,17,.02212,-.03273,
.0161,-.036074,
.009592,-.038322,
.002791,-.039405,
-.004094,-.039291,
-.010854,-.037983,
-.017285,-.035521,
-.02212,-.03273,
-.02715,-.03775,
-.020182,-.041891,
-.012601,-.044759,
-.004638,-.046267,
.003467,-.04637,
.011466,-.045063,
.019117,-.042388,
.026188,-.038424,
.02715,-.03775,
.02212,-.03273,
0.0*
4,1,17,-.03273,-.02212,
-.036074,-.0161,
-.038322,-.009592,
-.039405,-.002791,
-.039291,.004094,
-.037983,.010854,
-.035521,.017285,
-.03273,.02212,
-.03775,.02715,
-.041891,.020182,
-.044759,.012601,
-.046267,.004638,
-.04637,-.003467,
-.045063,-.011466,
-.042388,-.019117,
-.038424,-.026188,
-.03775,-.02715,
-.03273,-.02212,
0.0*
4,1,17,-.02212,.03273,
-.0161,.036074,
-.009592,.038322,
-.002791,.039405,
.004094,.039291,
.010854,.037983,
.017285,.035521,
.02212,.03273,
.02715,.03775,
.020182,.041891,
.012601,.044759,
.004638,.046267,
-.003467,.04637,
-.011466,.045063,
-.019117,.042388,
-.026188,.038424,
-.02715,.03775,
-.02212,.03273,
0.0*
%
%ADD21MACRO21*%
%ADD41O,.235X.274*%
%ADD19C,.125*%
%ADD12C,.162*%
%ADD40C,.235*%
%ADD42C,.345*%
%ADD31C,.129*%
%ADD14C,.156*%
%AMMACRO20*
4,1,36,0.0,.013,
-.002257,.012803,
-.004446,.012216,
-.0065,.011258,
-.008356,.009959,
-.009959,.008356,
-.011258,.0065,
-.012216,.004446,
-.012803,.002257,
-.013,0.0,
-.012803,-.002257,
-.012216,-.004446,
-.011258,-.0065,
-.009959,-.008356,
-.008356,-.009959,
-.0065,-.011258,
-.004446,-.012216,
-.002257,-.012803,
0.0,-.013,
.002257,-.012803,
.004446,-.012216,
.0065,-.011258,
.008356,-.009959,
.009959,-.008356,
.011258,-.0065,
.012216,-.004446,
.012803,-.002257,
.013,0.0,
.012803,.002257,
.012216,.004446,
.011258,.0065,
.009959,.008356,
.008356,.009959,
.0065,.011258,
.004446,.012216,
.002257,.012803,
0.0,.013,
270.*
%
%ADD20MACRO20*%
%AMMACRO32*
4,1,36,0.0,.009,
.001563,.008863,
.003078,.008457,
.0045,.007794,
.005785,.006894,
.006894,.005785,
.007794,.0045,
.008457,.003078,
.008863,.001563,
.009,0.0,
.008863,-.001563,
.008457,-.003078,
.007794,-.0045,
.006894,-.005785,
.005785,-.006894,
.0045,-.007794,
.003078,-.008457,
.001563,-.008863,
0.0,-.009,
-.001563,-.008863,
-.003078,-.008457,
-.0045,-.007794,
-.005785,-.006894,
-.006894,-.005785,
-.007794,-.0045,
-.008457,-.003078,
-.008863,-.001563,
-.009,0.0,
-.008863,.001563,
-.008457,.003078,
-.007794,.0045,
-.006894,.005785,
-.005785,.006894,
-.0045,.007794,
-.003078,.008457,
-.001563,.008863,
0.0,.009,
180.*
%
%ADD32MACRO32*%
%AMMACRO36*
4,1,36,0.0,.014,
.002431,.013787,
.004788,.013156,
.007,.012124,
.008999,.010725,
.010725,.008999,
.012124,.007,
.013156,.004788,
.013787,.002431,
.014,0.0,
.013787,-.002431,
.013156,-.004788,
.012124,-.007,
.010725,-.008999,
.008999,-.010725,
.007,-.012124,
.004788,-.013156,
.002431,-.013787,
0.0,-.014,
-.002431,-.013787,
-.004788,-.013156,
-.007,-.012124,
-.008999,-.010725,
-.010725,-.008999,
-.012124,-.007,
-.013156,-.004788,
-.013787,-.002431,
-.014,0.0,
-.013787,.002431,
-.013156,.004788,
-.012124,.007,
-.010725,.008999,
-.008999,.010725,
-.007,.012124,
-.004788,.013156,
-.002431,.013787,
0.0,.014,
180.*
%
%ADD36MACRO36*%
%ADD28C,.188*%
%AMMACRO11*
4,1,36,0.0,.004,
.000695,.003939,
.001368,.003759,
.002,.003464,
.002571,.003064,
.003064,.002571,
.003464,.002,
.003759,.001368,
.003939,.000695,
.004,0.0,
.003939,-.000695,
.003759,-.001368,
.003464,-.002,
.003064,-.002571,
.002571,-.003064,
.002,-.003464,
.001368,-.003759,
.000695,-.003939,
0.0,-.004,
-.000695,-.003939,
-.001368,-.003759,
-.002,-.003464,
-.002571,-.003064,
-.003064,-.002571,
-.003464,-.002,
-.003759,-.001368,
-.003939,-.000695,
-.004,0.0,
-.003939,.000695,
-.003759,.001368,
-.003464,.002,
-.003064,.002571,
-.002571,.003064,
-.002,.003464,
-.001368,.003759,
-.000695,.003939,
0.0,.004,
0.0*
%
%ADD11MACRO11*%
%AMMACRO30*
4,1,16,.02584,.01524,
.028094,.010521,
.029494,.005483,
.029998,.000278,
.029591,-.004935,
.028284,-.009999,
.026118,-.014758,
.02584,-.01524,
.03092,-.02032,
.033979,-.014642,
.036005,-.008519,
.036938,-.002138,
.036748,.004309,
.035441,.010625,
.033058,.016618,
.03092,.02032,
.02584,.01524,
270.*
4,1,16,.01524,-.02584,
.010521,-.028094,
.005483,-.029494,
.000278,-.029998,
-.004935,-.029591,
-.009999,-.028284,
-.014758,-.026118,
-.01524,-.02584,
-.02032,-.03092,
-.014642,-.033979,
-.008519,-.036005,
-.002138,-.036938,
.004309,-.036748,
.010625,-.035441,
.016618,-.033058,
.02032,-.03092,
.01524,-.02584,
270.*
4,1,16,-.02584,-.01524,
-.028094,-.010521,
-.029494,-.005483,
-.029998,-.000278,
-.029591,.004935,
-.028284,.009999,
-.026118,.014758,
-.02584,.01524,
-.03092,.02032,
-.033979,.014642,
-.036005,.008519,
-.036938,.002138,
-.036748,-.004309,
-.035441,-.010625,
-.033058,-.016618,
-.03092,-.02032,
-.02584,-.01524,
270.*
4,1,16,-.01524,.02584,
-.010521,.028094,
-.005483,.029494,
-.000278,.029998,
.004935,.029591,
.009999,.028284,
.014758,.026118,
.01524,.02584,
.02032,.03092,
.014642,.033979,
.008519,.036005,
.002138,.036938,
-.004309,.036748,
-.010625,.035441,
-.016618,.033058,
-.02032,.03092,
-.01524,.02584,
270.*
%
%ADD30MACRO30*%
%AMMACRO37*
4,1,15,.02291,.0123,
.024698,.008135,
.025735,.003723,
.025991,-.000803,
.025456,-.005304,
.024149,-.009644,
.02291,-.0123,
.02803,-.01742,
.030629,-.012288,
.032298,-.006783,
.032985,-.001071,
.03267,.004673,
.031362,.010275,
.029101,.015565,
.02803,.01742,
.02291,.0123,
180.*
4,1,15,.0123,-.02291,
.008135,-.024698,
.003723,-.025735,
-.000803,-.025991,
-.005304,-.025456,
-.009644,-.024149,
-.0123,-.02291,
-.01742,-.02803,
-.012288,-.030629,
-.006783,-.032298,
-.001071,-.032985,
.004673,-.03267,
.010275,-.031362,
.015565,-.029101,
.01742,-.02803,
.0123,-.02291,
180.*
4,1,15,-.02291,-.0123,
-.024698,-.008135,
-.025735,-.003723,
-.025991,.000803,
-.025456,.005304,
-.024149,.009644,
-.02291,.0123,
-.02803,.01742,
-.030629,.012288,
-.032298,.006783,
-.032985,.001071,
-.03267,-.004673,
-.031362,-.010275,
-.029101,-.015565,
-.02803,-.01742,
-.02291,-.0123,
180.*
4,1,15,-.0123,.02291,
-.008135,.024698,
-.003723,.025735,
.000803,.025991,
.005304,.025456,
.009644,.024149,
.0123,.02291,
.01742,.02803,
.012288,.030629,
.006783,.032298,
.001071,.032985,
-.004673,.03267,
-.010275,.031362,
-.015565,.029101,
-.01742,.02803,
-.0123,.02291,
180.*
%
%ADD37MACRO37*%
%AMMACRO24*
4,1,15,.02401,.0134,
.025972,.009027,
.027145,.00438,
.027493,-.0004,
.027006,-.005168,
.025698,-.009779,
.02401,-.0134,
.02912,-.01851,
.031892,-.013172,
.033695,-.007434,
.034474,-.00147,
.034205,.004538,
.032897,.010409,
.03059,.015964,
.02912,.01851,
.02401,.0134,
180.*
4,1,15,.0134,-.02401,
.009027,-.025972,
.00438,-.027145,
-.0004,-.027493,
-.005168,-.027006,
-.009779,-.025698,
-.0134,-.02401,
-.01851,-.02912,
-.013172,-.031892,
-.007434,-.033695,
-.00147,-.034474,
.004538,-.034205,
.010409,-.032897,
.015964,-.03059,
.01851,-.02912,
.0134,-.02401,
180.*
4,1,15,-.02401,-.0134,
-.025972,-.009027,
-.027145,-.00438,
-.027493,.0004,
-.027006,.005168,
-.025698,.009779,
-.02401,.0134,
-.02912,.01851,
-.031892,.013172,
-.033695,.007434,
-.034474,.00147,
-.034205,-.004538,
-.032897,-.010409,
-.03059,-.015964,
-.02912,-.01851,
-.02401,-.0134,
180.*
4,1,15,-.0134,.02401,
-.009027,.025972,
-.00438,.027145,
.0004,.027493,
.005168,.027006,
.009779,.025698,
.0134,.02401,
.01851,.02912,
.013172,.031892,
.007434,.033695,
.00147,.034474,
-.004538,.034205,
-.010409,.032897,
-.015964,.03059,
-.01851,.02912,
-.0134,.02401,
180.*
%
%ADD24MACRO24*%
%AMMACRO23*
4,1,17,.03056,.01996,
.033562,.01435,
.035544,.008304,
.036446,.002006,
.03624,-.004353,
.034934,-.01058,
.032566,-.016486,
.03056,-.01996,
.0356,-.025,
.0394,-.018438,
.042004,-.011316,
.043331,-.003851,
.043341,.003732,
.042034,.011201,
.039451,.018331,
.035668,.024903,
.0356,.025,
.03056,.01996,
270.*
4,1,17,.01996,-.03056,
.01435,-.033562,
.008304,-.035544,
.002006,-.036446,
-.004353,-.03624,
-.01058,-.034934,
-.016486,-.032566,
-.01996,-.03056,
-.025,-.0356,
-.018438,-.0394,
-.011316,-.042004,
-.003851,-.043331,
.003732,-.043341,
.011201,-.042034,
.018331,-.039451,
.024903,-.035668,
.025,-.0356,
.01996,-.03056,
270.*
4,1,17,-.03056,-.01996,
-.033562,-.01435,
-.035544,-.008304,
-.036446,-.002006,
-.03624,.004353,
-.034934,.01058,
-.032566,.016486,
-.03056,.01996,
-.0356,.025,
-.0394,.018438,
-.042004,.011316,
-.043331,.003851,
-.043341,-.003732,
-.042034,-.011201,
-.039451,-.018331,
-.035668,-.024903,
-.0356,-.025,
-.03056,-.01996,
270.*
4,1,17,-.01996,.03056,
-.01435,.033562,
-.008304,.035544,
-.002006,.036446,
.004353,.03624,
.01058,.034934,
.016486,.032566,
.01996,.03056,
.025,.0356,
.018438,.0394,
.011316,.042004,
.003851,.043331,
-.003732,.043341,
-.011201,.042034,
-.018331,.039451,
-.024903,.035668,
-.025,.0356,
-.01996,.03056,
270.*
%
%ADD23MACRO23*%
%AMMACRO15*
4,1,17,.03273,.02212,
.036074,.0161,
.038322,.009592,
.039405,.002791,
.039291,-.004094,
.037983,-.010854,
.035521,-.017285,
.03273,-.02212,
.03775,-.02715,
.041891,-.020182,
.044759,-.012601,
.046267,-.004638,
.04637,.003467,
.045063,.011466,
.042388,.019117,
.038424,.026188,
.03775,.02715,
.03273,.02212,
180.*
4,1,17,.02212,-.03273,
.0161,-.036074,
.009592,-.038322,
.002791,-.039405,
-.004094,-.039291,
-.010854,-.037983,
-.017285,-.035521,
-.02212,-.03273,
-.02715,-.03775,
-.020182,-.041891,
-.012601,-.044759,
-.004638,-.046267,
.003467,-.04637,
.011466,-.045063,
.019117,-.042388,
.026188,-.038424,
.02715,-.03775,
.02212,-.03273,
180.*
4,1,17,-.03273,-.02212,
-.036074,-.0161,
-.038322,-.009592,
-.039405,-.002791,
-.039291,.004094,
-.037983,.010854,
-.035521,.017285,
-.03273,.02212,
-.03775,.02715,
-.041891,.020182,
-.044759,.012601,
-.046267,.004638,
-.04637,-.003467,
-.045063,-.011466,
-.042388,-.019117,
-.038424,-.026188,
-.03775,-.02715,
-.03273,-.02212,
180.*
4,1,17,-.02212,.03273,
-.0161,.036074,
-.009592,.038322,
-.002791,.039405,
.004094,.039291,
.010854,.037983,
.017285,.035521,
.02212,.03273,
.02715,.03775,
.020182,.041891,
.012601,.044759,
.004638,.046267,
-.003467,.04637,
-.011466,.045063,
-.019117,.042388,
-.026188,.038424,
-.02715,.03775,
-.02212,.03273,
180.*
%
%ADD15MACRO15*%
%ADD43C,.006*%
%ADD54C,.24506*%
%ADD53O,.24504X.28404*%
%ADD52C,.13238*%
%ADD49C,.16406*%
%ADD51C,.12717*%
%ADD46C,.13266*%
%ADD50C,.15806*%
%ADD47C,.35606*%
%ADD45C,.21954*%
%ADD44C,.24475*%
%ADD48C,.19786*%
G75*
%LPD*%
G75*
G36*
G01X-723776Y-489221D02*
X1782976D01*
Y2987387D01*
X-723776D01*
Y-489221D01*
G37*
%LPC*%
G75*
G36*
G01X397638Y2084610D02*
G02X403508Y2078740I0J-5870D01*
G01Y7874D01*
G02X397638Y2004I-5870J0D01*
G01X104331D01*
G02X100429Y5906I0J3902D01*
G01Y9843D01*
G03X92520Y17752I-7909J0D01*
G01X5906D01*
G02X2004Y21654I0J3902D01*
G01Y2064961D01*
G02X5905Y2068862I3901J0D01*
G01X92520D01*
G03X100429Y2076772I0J7909D01*
G01Y2080709D01*
G02X104331Y2084610I3902J-1D01*
G01X397638D01*
G37*
%LPD*%
G75*
G36*
G01X17976Y989245D02*
Y990190D01*
G02X22970Y990185I2491J-5857D01*
G01Y989240D01*
G03X23209Y988813I500J0D01*
G02X23856Y988346I-2741J-4480D01*
G01X25407D01*
G02X14103Y984333I-4940J-4013D01*
G02X15503Y988316I6365J0D01*
G01X17045D01*
G02X17736Y988818I3422J-3984D01*
G03X17976Y989245I-260J427D01*
G37*
G36*
G01X17980Y1347510D02*
Y1348455D01*
G02X22974Y1348450I2491J-5857D01*
G01Y1347505D01*
G03X23213Y1347078I500J0D01*
G02X23859Y1346612I-2741J-4480D01*
G01X25411D01*
G02X14107Y1342598I-4939J-4014D01*
G02X15507Y1346580I6365J-1D01*
G01X17048D01*
G02X17740Y1347083I3424J-3982D01*
G03X17980Y1347510I-260J427D01*
G37*
G54D54*
X307086Y308267D03*
G54D53*
Y1883071D03*
G54D52*
X163385Y27205D03*
Y202205D03*
Y377205D03*
X163386Y552205D03*
Y727205D03*
X163385Y902205D03*
Y1077205D03*
Y1252205D03*
Y1427205D03*
Y1602205D03*
Y1777205D03*
Y1952205D03*
G54D49*
X57735Y2026661D03*
Y1922291D03*
Y390834D03*
Y268811D03*
Y181976D03*
Y59953D03*
X12735Y2026661D03*
Y1922291D03*
Y390834D03*
Y268811D03*
Y181976D03*
Y59953D03*
G54D51*
X20472Y1054606D03*
G54D46*
X373385Y1957520D03*
Y1782520D03*
Y1607520D03*
Y1432520D03*
Y1257520D03*
Y1082520D03*
Y907520D03*
X373386Y732520D03*
Y557520D03*
X373385Y382520D03*
Y207520D03*
Y32520D03*
G54D50*
X58995Y1587992D03*
Y543701D03*
X13995Y1587992D03*
Y543701D03*
G54D47*
X359842Y2003780D03*
Y1828779D03*
Y1653780D03*
Y1478780D03*
Y1303780D03*
Y1128779D03*
Y953780D03*
Y778780D03*
Y603779D03*
Y428779D03*
Y253780D03*
Y78780D03*
G54D45*
X370297Y1883108D03*
G54D44*
X370078Y308268D03*
G54D48*
X307087Y2043503D03*
X307086Y1693504D03*
Y1343504D03*
Y827165D03*
Y477165D03*
Y127165D03*
X65354Y1864960D03*
Y1514960D03*
Y1164960D03*
Y814960D03*
Y464960D03*
Y114960D03*
G54D26*
X48433Y866179D03*
X48467Y869278D03*
X49441Y1238962D03*
X46980Y1335843D03*
Y1325843D03*
Y1315843D03*
Y1320843D03*
Y1330843D03*
Y1345843D03*
Y1340843D03*
X57124Y675327D03*
X54483Y679810D03*
X59236Y670758D03*
X70865Y854278D03*
Y872278D03*
Y866278D03*
Y860278D03*
Y897750D03*
Y890116D03*
X60815Y1019026D03*
X63577Y1019115D03*
X59127Y1257647D03*
X58356Y1279812D03*
X58416Y1272383D03*
X61866Y1309190D03*
X67568Y1307829D03*
X54543Y1308995D03*
X61866Y1342104D03*
X93223Y417736D03*
X94347Y421562D03*
X95775Y751469D03*
X92216Y899865D03*
X90708Y878615D03*
X92633Y907404D03*
X92989Y927334D03*
X98139Y990959D03*
X76446Y1014871D03*
X79499D03*
X82763Y1060051D03*
X96684Y1081791D03*
X96510Y1395382D03*
X95236Y1453321D03*
X106958Y26285D03*
X101430Y41803D03*
X107405Y49898D03*
X107037Y34687D03*
X104350Y62293D03*
X107263Y72244D03*
X109054Y58250D03*
X107213Y85169D03*
X106836Y376461D03*
X106709Y391219D03*
X105451Y406795D03*
X114498Y396207D03*
X109475Y434743D03*
X111017Y419566D03*
X107025Y725368D03*
X105087Y754126D03*
X106935Y745139D03*
X107173Y735219D03*
X112836Y769122D03*
X113697Y794293D03*
X105395Y972040D03*
X102611Y972220D03*
X100687Y999391D03*
X107351Y1093484D03*
X107235Y1081791D03*
X107215Y1072208D03*
X108779Y1105760D03*
X105152Y1118381D03*
X112503Y1115860D03*
X108468Y1129286D03*
X100719Y1312810D03*
Y1306810D03*
Y1330810D03*
Y1336810D03*
Y1324810D03*
Y1318810D03*
Y1346065D03*
X101626Y1397635D03*
X106962Y1434041D03*
X106921Y1419492D03*
X106763Y1444599D03*
X107006Y1452651D03*
X108574Y1463389D03*
X113518Y1489571D03*
X107355Y1770437D03*
X107391Y1794460D03*
X107220Y1791589D03*
X107373Y1780544D03*
X108819Y1812118D03*
X106819Y1802230D03*
X108819Y1824470D03*
X144878Y1738861D03*
X157558Y51426D03*
X161339Y88108D03*
X159417Y91281D03*
X158901Y85017D03*
X156865Y401207D03*
X161517Y436119D03*
X159019Y439268D03*
X158807Y432969D03*
X156610Y751063D03*
X158956Y780982D03*
X161479Y784141D03*
X159053Y787280D03*
X156854Y1101031D03*
X159382Y1136151D03*
X158456Y1129045D03*
X158618Y1399448D03*
X164037Y1400226D03*
X170351Y1401324D03*
X159192Y1451105D03*
X159216Y1477124D03*
X159526Y1483434D03*
X150309Y1737009D03*
X168151Y1739208D03*
X156183Y1735240D03*
X165782Y1732903D03*
X163257Y1737619D03*
X156452Y1800821D03*
X161844Y1828225D03*
X159822Y1831380D03*
X159075Y1825087D03*
X175989Y944537D03*
X176011Y936829D03*
X175359Y963486D03*
X175561Y955964D03*
X175135Y972490D03*
X175022Y980281D03*
X175742Y989958D03*
X175449Y997660D03*
X175698Y1008730D03*
X175473Y1016296D03*
X175448Y1031766D03*
X175897Y1023997D03*
X176083Y1402321D03*
X173394Y1736051D03*
X256947Y128276D03*
X257125Y115559D03*
X265722Y463102D03*
X265737Y473680D03*
X255837Y823626D03*
X255687Y812192D03*
X280240Y1858668D03*
X279976Y1864565D03*
X308057Y248863D03*
X306267Y241010D03*
X314914Y238162D03*
X314940Y252083D03*
X305867Y258589D03*
X309678Y1053262D03*
X312527Y1162266D03*
X312698Y1172804D03*
X314183Y1403423D03*
X302267Y1524401D03*
X301734Y1513883D03*
X312077Y1575871D03*
X311539Y1753499D03*
X292614Y1864565D03*
X331403Y51409D03*
X333889Y56021D03*
X338227Y61559D03*
X320372Y225979D03*
X318088Y231820D03*
X321899Y238137D03*
X329930Y245684D03*
X331046Y232021D03*
X320961Y250105D03*
X324709Y231580D03*
X335522Y404033D03*
X323313Y418313D03*
X326196Y413982D03*
X328950Y409216D03*
X320980Y423225D03*
X336617Y577978D03*
X319305Y582111D03*
X329636Y584715D03*
X317724Y588250D03*
X337387Y586230D03*
X320380Y576491D03*
X331867Y589810D03*
X333750Y595326D03*
X323751Y589155D03*
X319852Y593330D03*
X321742Y599041D03*
X331568Y752967D03*
X339012Y752859D03*
X329336Y762693D03*
X334010Y758588D03*
X327524Y758020D03*
X339615Y926357D03*
X329938Y948756D03*
X332527Y943746D03*
X324098Y946104D03*
X318557Y941178D03*
X323868Y929978D03*
X326646Y939788D03*
X333300Y928464D03*
X336160Y937262D03*
X328583Y933262D03*
X321425Y951577D03*
X324246Y1051786D03*
X335677Y1048904D03*
X317592Y1053050D03*
X331920Y1116088D03*
X337509Y1109598D03*
X328989Y1121090D03*
X326558Y1126368D03*
X323403Y1172804D03*
X327452Y1279447D03*
X321978Y1282086D03*
X338047Y1282599D03*
X333242Y1276809D03*
X329619Y1284016D03*
X327932Y1289221D03*
X319404Y1401346D03*
X325636Y1399114D03*
X334646Y1400804D03*
X323720Y1570924D03*
X329399Y1571939D03*
X317243Y1574832D03*
X333474Y1566686D03*
X335963Y1573797D03*
X329887Y1752081D03*
X321283Y1753466D03*
X335730Y1753270D03*
X338309Y1927623D03*
X332399Y1926787D03*
X359931Y52189D03*
X348289Y50863D03*
X345089Y56190D03*
X340373Y51579D03*
X342097Y401684D03*
X363825Y401768D03*
X342900Y580126D03*
X362577Y752783D03*
X344109Y751809D03*
X343656Y933725D03*
X345578Y1047844D03*
X344099Y1106798D03*
X349855Y1104302D03*
X344130Y1401670D03*
X350690Y1403243D03*
X348710Y1570187D03*
X361011Y1568890D03*
X343402Y1572080D03*
X348245Y1575241D03*
X355364Y1570990D03*
X345537Y1916558D03*
X344402Y1911123D03*
X363361Y1918313D03*
X358318Y1920680D03*
X363411Y1923459D03*
X340336Y1922409D03*
X347676Y1922165D03*
X372204Y56126D03*
X365720Y52336D03*
X379257Y52158D03*
X379572Y58441D03*
X387524Y76847D03*
X374442Y406857D03*
X380619Y410112D03*
X380878Y403999D03*
X374542Y401282D03*
X368907Y404308D03*
X376654Y754748D03*
X382892Y767710D03*
X386790Y774338D03*
X380186Y761742D03*
X379335Y1189778D03*
X383276Y1184136D03*
X386816Y1179841D03*
X376472Y1194999D03*
X373674Y1199967D03*
X371523Y1204725D03*
X367829Y1566108D03*
X374775Y1919243D03*
X379403Y1917261D03*
X369748Y1921795D03*
X391278Y765894D03*
G54D34*
X165975Y265783D03*
Y296140D03*
Y286803D03*
Y276298D03*
Y312307D03*
Y303868D03*
X157272Y604773D03*
Y633416D03*
Y613574D03*
Y624079D03*
Y641144D03*
Y649583D03*
X166699Y972924D03*
Y983439D03*
Y993944D03*
X166424Y1011298D03*
Y1003570D03*
Y1019737D03*
X155749Y1307733D03*
Y1328753D03*
Y1318248D03*
Y1354257D03*
Y1338090D03*
Y1345818D03*
X158492Y1667763D03*
Y1657248D03*
Y1695333D03*
Y1687605D03*
Y1678268D03*
Y1703772D03*
X219214Y1287272D03*
Y1301975D03*
X219349Y1308924D03*
X219214Y1294491D03*
X219178Y1324285D03*
Y1332321D03*
Y1316842D03*
Y1339840D03*
X243741Y153964D03*
X222732D03*
X232700D03*
X243741Y170131D03*
Y161692D03*
X222732Y170131D03*
Y161692D03*
X232700Y170131D03*
Y161692D03*
X239746Y407393D03*
Y396878D03*
Y417898D03*
X243980Y754782D03*
X234012D03*
X243980Y762510D03*
Y770949D03*
X234012Y762510D03*
Y770949D03*
X226642Y1287272D03*
Y1301975D03*
X235465D03*
X226777Y1308924D03*
X235600D03*
X242961Y1301975D03*
X243096Y1308924D03*
X226642Y1294491D03*
X235465D03*
X242961D03*
X226606Y1324285D03*
X235429D03*
X226606Y1332321D03*
X235429D03*
X242925Y1324285D03*
Y1332321D03*
X226606Y1316842D03*
X235429D03*
X242925D03*
X226606Y1339840D03*
X235429D03*
X242925D03*
X224573Y2031480D03*
X234541D03*
X224573Y2020965D03*
X234541D03*
X224573Y2059050D03*
X234541Y2051322D03*
Y2059050D03*
X224573Y2041985D03*
Y2051322D03*
X234541Y2041985D03*
Y2067489D03*
X224573D03*
X256566Y54944D03*
X264104D03*
X256566Y45572D03*
X264104D03*
X256566Y65449D03*
X264104D03*
X264861Y153964D03*
X253083D03*
X264861Y170131D03*
Y161692D03*
X253083Y170131D03*
Y161692D03*
X264596Y221664D03*
X252818D03*
X264596Y242684D03*
Y232179D03*
X252818Y242684D03*
Y232179D03*
X264596Y268188D03*
Y259749D03*
Y252021D03*
X252818Y268188D03*
Y252021D03*
Y259749D03*
X266040Y407146D03*
Y396631D03*
Y417651D03*
X257572Y396630D03*
Y407145D03*
X248714Y407536D03*
Y397021D03*
X257572Y417650D03*
X248714Y418041D03*
X267166Y581440D03*
Y572639D03*
Y609010D03*
Y601282D03*
Y591945D03*
Y617449D03*
X255021Y754782D03*
Y762510D03*
Y770949D03*
X263174Y855159D03*
Y862887D03*
X251396D03*
Y855159D03*
Y871326D03*
X263174D03*
X262766Y949344D03*
Y967106D03*
Y959859D03*
X262621Y974386D03*
Y990553D03*
Y982114D03*
X261219Y1124364D03*
Y1134879D03*
X251251Y1124364D03*
Y1134879D03*
X261219Y1145384D03*
X251251D03*
X259581Y1272430D03*
Y1282945D03*
Y1293450D03*
Y1302787D03*
Y1310515D03*
Y1318954D03*
X263939Y1548010D03*
Y1534139D03*
Y1541055D03*
X261564Y1621823D03*
Y1642843D03*
Y1632338D03*
Y1668347D03*
Y1659908D03*
Y1652180D03*
X265759Y1697613D03*
X254718D03*
X265759Y1676593D03*
Y1687108D03*
X254718D03*
Y1676593D03*
X254457Y1722140D03*
X265498D03*
X265759Y1714678D03*
X254718D03*
Y1706950D03*
X265759D03*
X258639Y1819074D03*
Y1812119D03*
Y1805203D03*
X250468Y1819074D03*
Y1812119D03*
Y1805203D03*
X267396Y1819077D03*
Y1805206D03*
Y1812122D03*
X258459Y1826219D03*
X250288D03*
X267037Y1826222D03*
X258459Y1840090D03*
Y1833135D03*
X267037Y1833138D03*
Y1840093D03*
X250288Y1833135D03*
Y1840090D03*
X245582Y2031480D03*
Y2020965D03*
X258337D03*
Y2031480D03*
X245582Y2041985D03*
Y2051322D03*
Y2059050D03*
X258337Y2051322D03*
Y2059050D03*
Y2041985D03*
Y2067489D03*
X245582D03*
X288102Y54944D03*
Y45572D03*
X271572Y54944D03*
X279754D03*
X271572Y45572D03*
X279754D03*
X288102Y65449D03*
X271572D03*
X279754D03*
X274531Y407289D03*
Y396774D03*
Y417794D03*
X278944Y581440D03*
Y572639D03*
Y601282D03*
Y609010D03*
Y591945D03*
Y617449D03*
X274544Y949344D03*
Y967106D03*
Y959859D03*
X274399Y974386D03*
Y990553D03*
Y982114D03*
X279015Y1124077D03*
X288363Y1123935D03*
X279015Y1134592D03*
X288363Y1134450D03*
X269975Y1134735D03*
Y1124220D03*
X288363Y1144955D03*
X279015Y1145097D03*
X269975Y1145240D03*
X286721Y1184312D03*
Y1192040D03*
X278182Y1184455D03*
Y1192183D03*
X286721Y1200479D03*
X278182Y1200622D03*
X270622Y1282945D03*
Y1272430D03*
Y1293450D03*
Y1302787D03*
Y1310515D03*
Y1318954D03*
X278400Y1548190D03*
X271534Y1548010D03*
X285995Y1548190D03*
X278400Y1534319D03*
Y1541235D03*
X271534Y1534139D03*
Y1541055D03*
X285995Y1534319D03*
Y1541235D03*
X273342Y1621823D03*
Y1642843D03*
Y1632338D03*
Y1668347D03*
Y1652180D03*
Y1659908D03*
X270115Y2031480D03*
Y2020965D03*
Y2051322D03*
Y2059050D03*
Y2041985D03*
Y2067489D03*
X300537Y516309D03*
X307966Y516419D03*
Y524147D03*
X300537Y524037D03*
Y532476D03*
X307966Y532586D03*
X292569Y524323D03*
Y516595D03*
Y532762D03*
X315187Y652457D03*
Y661258D03*
X304146D03*
Y652457D03*
Y681100D03*
X315187D03*
Y671763D03*
X304146D03*
X315187Y688828D03*
X304146D03*
Y697267D03*
X315187D03*
X307194Y1020657D03*
X307078Y1007303D03*
X307274Y1001286D03*
X307143Y1014094D03*
X307129Y1027081D03*
X306999Y1033718D03*
X303159Y1184526D03*
Y1192254D03*
X311936Y1192253D03*
Y1184525D03*
X294691Y1184526D03*
Y1192254D03*
X311936Y1200692D03*
X303159Y1200693D03*
X294691D03*
X309823Y1472957D03*
X309464Y1480102D03*
X309823Y1466002D03*
Y1459086D03*
X292715Y1480099D03*
X292895Y1472954D03*
X301066D03*
X300886Y1480099D03*
X292895Y1459083D03*
Y1465999D03*
X301066D03*
Y1459083D03*
X309464Y1493973D03*
Y1487018D03*
X292715Y1487015D03*
Y1493970D03*
X300886D03*
Y1487015D03*
X292754Y1917148D03*
X300349D03*
X292754Y1910232D03*
X300349D03*
X307215Y1910412D03*
X314810D03*
Y1917328D03*
X307215D03*
X292754Y1924103D03*
X300349D03*
X314810Y1924283D03*
X307215D03*
X332775Y318634D03*
X332693Y311980D03*
X332775Y335272D03*
Y342461D03*
Y325935D03*
X332685Y348655D03*
X325139Y516632D03*
Y524360D03*
X316791Y524432D03*
Y516704D03*
Y532871D03*
X325139Y532799D03*
X318235Y1020657D03*
X318315Y1001286D03*
X318119Y1007303D03*
X318184Y1014094D03*
X318170Y1027081D03*
X318040Y1033718D03*
X343816Y318634D03*
X343734Y311980D03*
X343816Y335272D03*
Y342461D03*
Y325935D03*
X343726Y348655D03*
G54D38*
X253385Y21890D03*
Y32520D03*
X263385Y21890D03*
Y32520D03*
X253385Y196890D03*
X263385D03*
X253385Y207520D03*
X263385D03*
X253385Y371890D03*
X263385D03*
X253385Y382520D03*
X263385D03*
X253386Y546890D03*
Y557520D03*
X263386Y546890D03*
Y557520D03*
X253386Y721890D03*
Y732520D03*
X263386Y721890D03*
Y732520D03*
X253385Y896890D03*
X263385D03*
X253385Y907520D03*
X263385D03*
X253385Y1071890D03*
X263385D03*
X253385Y1082520D03*
X263385D03*
X253385Y1246890D03*
Y1257520D03*
X263385Y1246890D03*
Y1257520D03*
X253385Y1421890D03*
Y1432520D03*
X263385Y1421890D03*
Y1432520D03*
X253385Y1596890D03*
X263385D03*
X253385Y1607520D03*
X263385D03*
X253385Y1771890D03*
X263385D03*
X253385Y1782520D03*
X263385D03*
X253385Y1946890D03*
Y1957520D03*
X263385Y1946890D03*
Y1957520D03*
X273385Y21890D03*
Y32520D03*
X283385Y21890D03*
Y32520D03*
X273385Y196890D03*
X283385D03*
X273385Y207520D03*
X283385D03*
X273385Y371890D03*
X283385D03*
X273385Y382520D03*
X283385D03*
X273386Y546890D03*
Y557520D03*
X283386Y546890D03*
Y557520D03*
X273386Y721890D03*
Y732520D03*
X283386Y721890D03*
Y732520D03*
X273385Y896890D03*
X283385D03*
X273385Y907520D03*
X283385D03*
X273385Y1071890D03*
X283385D03*
X273385Y1082520D03*
X283385D03*
X273385Y1246890D03*
Y1257520D03*
X283385Y1246890D03*
Y1257520D03*
X273385Y1421890D03*
Y1432520D03*
X283385Y1421890D03*
Y1432520D03*
X273385Y1596890D03*
X283385D03*
X273385Y1607520D03*
X283385D03*
X273385Y1771890D03*
X283385D03*
X273385Y1782520D03*
X283385D03*
X273385Y1946890D03*
Y1957520D03*
X283385Y1946890D03*
Y1957520D03*
X293385Y21890D03*
Y32520D03*
X303385Y21890D03*
Y32520D03*
X313385D03*
Y21890D03*
X293385Y196890D03*
X303385D03*
X313385D03*
X293385Y207520D03*
X303385D03*
X313385D03*
X293385Y371890D03*
X303385D03*
X313385D03*
X293385Y382520D03*
X303385D03*
X313385D03*
X293386Y546890D03*
Y557520D03*
X303386Y546890D03*
Y557520D03*
X313386D03*
Y546890D03*
X293386Y721890D03*
Y732520D03*
X303386Y721890D03*
Y732520D03*
X313386D03*
Y721890D03*
X293385Y896890D03*
X303385D03*
X313385D03*
X293385Y907520D03*
X303385D03*
X313385D03*
X293385Y1071890D03*
X303385D03*
X313385D03*
X293385Y1082520D03*
X303385D03*
X313385D03*
X293385Y1246890D03*
Y1257520D03*
X303385Y1246890D03*
Y1257520D03*
X313385D03*
Y1246890D03*
X293385Y1421890D03*
Y1432520D03*
X303385Y1421890D03*
Y1432520D03*
X313385D03*
Y1421890D03*
X293385Y1596890D03*
X303385D03*
X313385D03*
X293385Y1607520D03*
X303385D03*
X313385D03*
X293385Y1771890D03*
X303385D03*
X313385D03*
X293385Y1782520D03*
X303385D03*
X313385D03*
X293385Y1946890D03*
Y1957520D03*
X303385Y1946890D03*
Y1957520D03*
X313385D03*
Y1946890D03*
X337165Y24705D03*
X323385Y32520D03*
Y21890D03*
X337165Y34705D03*
Y199705D03*
X323385Y196890D03*
X337165Y209705D03*
X323385Y207520D03*
Y371890D03*
X337165Y374705D03*
Y384705D03*
X323385Y382520D03*
X337166Y549705D03*
Y559705D03*
X323386Y557520D03*
Y546890D03*
X337166Y724705D03*
X323386Y732520D03*
Y721890D03*
X337166Y734705D03*
X337165Y899705D03*
X323385Y896890D03*
X337165Y909705D03*
X323385Y907520D03*
Y1071890D03*
X337165Y1074705D03*
Y1084705D03*
X323385Y1082520D03*
X337165Y1249705D03*
Y1259705D03*
X323385Y1257520D03*
Y1246890D03*
X337165Y1424705D03*
Y1434705D03*
X323385Y1432520D03*
Y1421890D03*
X337165Y1599705D03*
X323385Y1596890D03*
X337165Y1609705D03*
X323385Y1607520D03*
Y1771890D03*
X337165Y1774705D03*
Y1784705D03*
X323385Y1782520D03*
X337165Y1949705D03*
Y1959705D03*
X323385Y1957520D03*
Y1946890D03*
X342165Y19705D03*
Y29705D03*
X347165Y24705D03*
X352165Y19705D03*
Y29705D03*
X357165Y24705D03*
X362165Y19705D03*
Y29705D03*
X347165Y34705D03*
X357165D03*
X342165Y194705D03*
X347165Y199705D03*
X352165Y194705D03*
X357165Y199705D03*
X362165Y194705D03*
X342165Y204705D03*
X347165Y209705D03*
X352165Y204705D03*
X357165Y209705D03*
X362165Y204705D03*
X342165Y369705D03*
X352165D03*
X362165D03*
X342165Y379705D03*
X347165Y374705D03*
Y384705D03*
X352165Y379705D03*
X357165Y374705D03*
Y384705D03*
X362165Y379705D03*
X342166Y544705D03*
Y554705D03*
X347166Y549705D03*
Y559705D03*
X352166Y544705D03*
Y554705D03*
X357166Y549705D03*
Y559705D03*
X362166Y544705D03*
Y554705D03*
X342166Y719705D03*
Y729705D03*
X347166Y724705D03*
X352166Y719705D03*
Y729705D03*
X357166Y724705D03*
X362166Y719705D03*
Y729705D03*
X347166Y734705D03*
X357166D03*
X342165Y894705D03*
X347165Y899705D03*
X352165Y894705D03*
X357165Y899705D03*
X362165Y894705D03*
X342165Y904705D03*
X347165Y909705D03*
X352165Y904705D03*
X357165Y909705D03*
X362165Y904705D03*
X342165Y1069705D03*
X352165D03*
X362165D03*
X342165Y1079705D03*
X347165Y1074705D03*
Y1084705D03*
X352165Y1079705D03*
X357165Y1074705D03*
Y1084705D03*
X362165Y1079705D03*
X342165Y1244705D03*
Y1254705D03*
X347165Y1249705D03*
Y1259705D03*
X352165Y1244705D03*
Y1254705D03*
X357165Y1249705D03*
Y1259705D03*
X362165Y1244705D03*
Y1254705D03*
X342165Y1419705D03*
Y1429705D03*
X347165Y1424705D03*
Y1434705D03*
X352165Y1419705D03*
Y1429705D03*
X357165Y1424705D03*
Y1434705D03*
X362165Y1419705D03*
Y1429705D03*
X342165Y1594705D03*
X347165Y1599705D03*
X352165Y1594705D03*
X357165Y1599705D03*
X362165Y1594705D03*
X342165Y1604705D03*
X347165Y1609705D03*
X352165Y1604705D03*
X357165Y1609705D03*
X362165Y1604705D03*
X342165Y1769705D03*
X352165D03*
X362165D03*
X342165Y1779705D03*
X347165Y1774705D03*
Y1784705D03*
X352165Y1779705D03*
X357165Y1774705D03*
Y1784705D03*
X362165Y1779705D03*
X342165Y1944705D03*
Y1954705D03*
X347165Y1949705D03*
Y1959705D03*
X352165Y1944705D03*
Y1954705D03*
X357165Y1949705D03*
Y1959705D03*
X362165Y1944705D03*
Y1954705D03*
G54D17*
X9606Y599901D03*
Y627264D03*
Y1471949D03*
Y1499311D03*
G54D27*
X65354Y101180D03*
X55511Y105117D03*
X51574Y114960D03*
X55511Y124803D03*
X65354Y128740D03*
Y451180D03*
X55511Y455117D03*
X51574Y464960D03*
X55511Y474803D03*
X65354Y478740D03*
Y801180D03*
X55511Y805117D03*
X51574Y814960D03*
X55511Y824803D03*
X65354Y828740D03*
Y1151180D03*
X55511Y1155117D03*
X51574Y1164960D03*
X55511Y1174803D03*
X65354Y1178740D03*
Y1501180D03*
X55511Y1505117D03*
X51574Y1514960D03*
X55511Y1524803D03*
X65354Y1528740D03*
Y1851180D03*
X55511Y1855117D03*
X51574Y1864960D03*
X55511Y1874803D03*
X65354Y1878740D03*
X75197Y105117D03*
Y124803D03*
X79134Y114960D03*
Y464960D03*
X75197Y455117D03*
Y474803D03*
Y805117D03*
Y824803D03*
X79134Y814960D03*
Y1164960D03*
X75197Y1155117D03*
Y1174803D03*
Y1505117D03*
Y1524803D03*
X79134Y1514960D03*
Y1864960D03*
X75197Y1855117D03*
Y1874803D03*
X307086Y113385D03*
X297243Y117322D03*
X293306Y127165D03*
X297243Y137008D03*
X307086Y140945D03*
Y463385D03*
X297243Y467322D03*
X293306Y477165D03*
X297243Y487008D03*
X307086Y490945D03*
Y813385D03*
X297243Y817322D03*
X293306Y827165D03*
X297243Y837008D03*
X307086Y840945D03*
Y1329724D03*
X297243Y1333661D03*
X293306Y1343504D03*
X297243Y1353347D03*
X307086Y1357284D03*
Y1679724D03*
X297243Y1683661D03*
X293306Y1693504D03*
X297243Y1703347D03*
X307086Y1707284D03*
X307087Y2029723D03*
X297244Y2033660D03*
X293307Y2043503D03*
X297244Y2053346D03*
X307087Y2057283D03*
X320866Y127165D03*
X316929Y117322D03*
Y137008D03*
Y467322D03*
Y487008D03*
X320866Y477165D03*
Y827165D03*
X316929Y817322D03*
Y837008D03*
Y1333661D03*
Y1353347D03*
X320866Y1343504D03*
Y1693504D03*
X316929Y1683661D03*
Y1703347D03*
X316930Y2033660D03*
Y2053346D03*
X320867Y2043503D03*
G54D29*
X119920Y18071D03*
Y28071D03*
Y38071D03*
Y48071D03*
Y58071D03*
Y68071D03*
Y78071D03*
Y88071D03*
Y218071D03*
Y228071D03*
Y238071D03*
Y248071D03*
Y258071D03*
Y268071D03*
Y278071D03*
Y288071D03*
Y298071D03*
Y308071D03*
Y318071D03*
Y328071D03*
Y366102D03*
Y376102D03*
Y386102D03*
Y396102D03*
Y406102D03*
Y416102D03*
Y426102D03*
Y436102D03*
Y566102D03*
Y576102D03*
Y586102D03*
Y596102D03*
Y606102D03*
Y616102D03*
Y626102D03*
Y636102D03*
Y646102D03*
Y656102D03*
Y666102D03*
Y676102D03*
Y714134D03*
Y724134D03*
Y734134D03*
Y744134D03*
Y754134D03*
Y764134D03*
Y774134D03*
Y784134D03*
Y914134D03*
Y924134D03*
Y934134D03*
Y944134D03*
Y954134D03*
Y964134D03*
Y974134D03*
Y984134D03*
Y994134D03*
Y1004134D03*
Y1014134D03*
Y1024134D03*
Y1062165D03*
Y1072165D03*
Y1082165D03*
Y1092165D03*
Y1102165D03*
Y1112165D03*
Y1122165D03*
Y1132165D03*
Y1262165D03*
Y1272165D03*
Y1282165D03*
Y1292165D03*
Y1302165D03*
Y1312165D03*
Y1322165D03*
Y1332165D03*
Y1342165D03*
Y1352165D03*
Y1362165D03*
Y1372165D03*
Y1410197D03*
Y1420197D03*
Y1430197D03*
Y1440197D03*
Y1450197D03*
Y1460197D03*
Y1470197D03*
Y1480197D03*
Y1610197D03*
Y1620197D03*
Y1630197D03*
Y1640197D03*
Y1650197D03*
Y1660197D03*
Y1670197D03*
Y1680197D03*
Y1690197D03*
Y1700197D03*
Y1710197D03*
Y1720197D03*
Y1758228D03*
Y1768228D03*
Y1778228D03*
Y1788228D03*
Y1798228D03*
Y1808228D03*
Y1818228D03*
Y1828228D03*
Y1958228D03*
Y1968228D03*
Y1978228D03*
Y1988228D03*
Y1998228D03*
Y2008228D03*
Y2018228D03*
Y2028228D03*
Y2038228D03*
Y2048228D03*
Y2058228D03*
Y2068228D03*
X139920Y28071D03*
Y18071D03*
Y58071D03*
Y48071D03*
Y38071D03*
Y78071D03*
Y68071D03*
Y88071D03*
Y228071D03*
Y218071D03*
Y248071D03*
Y238071D03*
Y268071D03*
Y258071D03*
Y298071D03*
Y288071D03*
Y278071D03*
Y318071D03*
Y308071D03*
Y328071D03*
Y366102D03*
Y396102D03*
Y386102D03*
Y376102D03*
Y416102D03*
Y406102D03*
Y436102D03*
Y426102D03*
Y566102D03*
Y586102D03*
Y576102D03*
Y606102D03*
Y596102D03*
Y636102D03*
Y626102D03*
Y616102D03*
Y656102D03*
Y646102D03*
Y676102D03*
Y666102D03*
Y734134D03*
Y724134D03*
Y714134D03*
Y754134D03*
Y744134D03*
Y774134D03*
Y764134D03*
Y784134D03*
Y924134D03*
Y914134D03*
Y944134D03*
Y934134D03*
Y974134D03*
Y964134D03*
Y954134D03*
Y994134D03*
Y984134D03*
Y1024134D03*
Y1014134D03*
Y1004134D03*
Y1072165D03*
Y1062165D03*
Y1092165D03*
Y1082165D03*
Y1122165D03*
Y1112165D03*
Y1102165D03*
Y1132165D03*
Y1262165D03*
Y1282165D03*
Y1272165D03*
Y1312165D03*
Y1302165D03*
Y1292165D03*
Y1332165D03*
Y1322165D03*
Y1362165D03*
Y1352165D03*
Y1342165D03*
Y1372165D03*
Y1410197D03*
Y1430197D03*
Y1420197D03*
Y1460197D03*
Y1450197D03*
Y1440197D03*
Y1480197D03*
Y1470197D03*
Y1620197D03*
Y1610197D03*
Y1650197D03*
Y1640197D03*
Y1630197D03*
Y1670197D03*
Y1660197D03*
Y1700197D03*
Y1690197D03*
Y1680197D03*
Y1720197D03*
Y1710197D03*
Y1768228D03*
Y1758228D03*
Y1798228D03*
Y1788228D03*
Y1778228D03*
Y1818228D03*
Y1808228D03*
Y1828228D03*
Y1958228D03*
Y1988228D03*
Y1978228D03*
Y1968228D03*
Y2008228D03*
Y1998228D03*
Y2038228D03*
Y2028228D03*
Y2018228D03*
Y2058228D03*
Y2048228D03*
Y2068228D03*
G54D13*
X18995Y508701D03*
X23995Y518701D03*
X21495Y559882D03*
X11692D03*
X21495Y1571811D03*
X11692D03*
X23995Y1622992D03*
X18995Y1612992D03*
X28995Y508701D03*
X38995D03*
X48995D03*
X33995Y518701D03*
X43995D03*
X51495Y559882D03*
Y1571811D03*
X43995Y1622992D03*
X33995D03*
X48995Y1612992D03*
X38995D03*
X28995D03*
X53995Y518701D03*
X61298Y559882D03*
Y1571811D03*
X53995Y1622992D03*
X203542Y73105D03*
X204069Y152050D03*
X204137Y247568D03*
X204597Y331786D03*
X203541Y421732D03*
X204333Y506517D03*
X206668Y598130D03*
X204596Y681645D03*
X205626Y774526D03*
X205386Y856244D03*
X210091Y947202D03*
X209296Y1032544D03*
X205030Y1122856D03*
X205122Y1206233D03*
X205626Y1299104D03*
X204332Y1380966D03*
X203243Y1474162D03*
X204859Y1557277D03*
X205923Y1648177D03*
X205387Y1731351D03*
X205310Y1823227D03*
X204069Y1900420D03*
X205905Y1998730D03*
X205310Y2043388D03*
G54D18*
X15547Y707364D03*
X25389D03*
X7673Y703427D03*
X15547Y715238D03*
Y730986D03*
X25389Y715238D03*
Y730986D03*
X7673Y711301D03*
Y719175D03*
Y727049D03*
X15547Y738860D03*
Y754608D03*
X25389Y738860D03*
Y754608D03*
X7673Y742797D03*
Y750671D03*
Y758545D03*
X15547Y762483D03*
Y770357D03*
Y778231D03*
X25389Y762483D03*
Y770357D03*
Y778231D03*
X7673Y774293D03*
Y782167D03*
X15547Y786105D03*
Y801853D03*
X25389Y786105D03*
Y801853D03*
X7673Y790041D03*
Y797915D03*
Y805790D03*
X15547Y809727D03*
Y817601D03*
X25389Y809727D03*
Y817601D03*
X7673Y813664D03*
Y821538D03*
Y829412D03*
X15547Y833349D03*
Y841223D03*
Y849097D03*
X25389Y833349D03*
Y841223D03*
Y849097D03*
X7673Y837286D03*
Y845160D03*
X15547Y856971D03*
Y872719D03*
X25389Y856971D03*
Y864845D03*
X7673Y860908D03*
Y868782D03*
Y876656D03*
X15547Y880593D03*
Y888467D03*
Y896341D03*
X25389Y880593D03*
Y888467D03*
Y896341D03*
X7673Y892404D03*
Y900278D03*
X15547Y912089D03*
Y919963D03*
X25389Y904215D03*
Y919963D03*
X7673Y908152D03*
Y916026D03*
X15547Y927837D03*
Y935711D03*
Y951459D03*
X25389Y927837D03*
Y935711D03*
Y943585D03*
X7673Y931774D03*
Y939648D03*
Y947522D03*
X15547Y959333D03*
Y967207D03*
Y975081D03*
X25389Y959333D03*
Y967207D03*
Y975081D03*
X7673Y955396D03*
Y971144D03*
Y979018D03*
Y994766D03*
X15547Y990829D03*
X25389D03*
Y998703D03*
X7673Y1002640D03*
Y1010514D03*
X15547Y1006577D03*
Y1014451D03*
Y1022325D03*
X25389Y1014451D03*
Y1022325D03*
X7673Y1026262D03*
X15551Y1065629D03*
X25393D03*
X7677Y1061692D03*
X15551Y1073503D03*
Y1081377D03*
X25393D03*
Y1089251D03*
X7677Y1077440D03*
Y1085314D03*
Y1093188D03*
X15551Y1097125D03*
Y1104999D03*
Y1112873D03*
Y1120748D03*
X25393Y1097125D03*
Y1104999D03*
Y1120748D03*
X7677Y1101062D03*
Y1116810D03*
X15551Y1136496D03*
Y1144370D03*
X25393Y1128622D03*
Y1136496D03*
Y1144370D03*
X7677Y1124684D03*
Y1132558D03*
Y1140432D03*
X15551Y1152244D03*
Y1160118D03*
X25393D03*
Y1167992D03*
X7677Y1156180D03*
Y1164055D03*
X15551Y1175866D03*
Y1183740D03*
Y1191614D03*
X25393Y1175866D03*
Y1183740D03*
X7677Y1171929D03*
Y1179803D03*
X15551Y1199488D03*
Y1215236D03*
X25393Y1199488D03*
Y1207362D03*
Y1215236D03*
X7677Y1195551D03*
Y1203425D03*
Y1211299D03*
X15551Y1223110D03*
Y1230984D03*
Y1238858D03*
X25393Y1223110D03*
Y1238858D03*
X7677Y1219173D03*
Y1234921D03*
X15551Y1254606D03*
Y1262480D03*
X25393Y1246732D03*
Y1254606D03*
X7677Y1242795D03*
Y1250669D03*
Y1258543D03*
X15551Y1270354D03*
Y1278228D03*
Y1286102D03*
X25393Y1278228D03*
X7677Y1274291D03*
X15551Y1293976D03*
Y1301850D03*
Y1309724D03*
X25393Y1293976D03*
Y1301850D03*
Y1309724D03*
X7677Y1290039D03*
Y1297913D03*
Y1305787D03*
X15551Y1317598D03*
Y1325472D03*
Y1333346D03*
X25393Y1325472D03*
Y1333346D03*
X7677Y1321535D03*
Y1329409D03*
Y1337283D03*
Y1353031D03*
X15551Y1349094D03*
X25393D03*
Y1356968D03*
X7677Y1368779D03*
Y1384527D03*
X15551Y1372716D03*
Y1380590D03*
X25393Y1364842D03*
Y1380590D03*
Y1388464D03*
X33263Y703427D03*
Y711301D03*
Y719175D03*
Y727049D03*
Y742797D03*
Y750671D03*
Y758545D03*
Y774293D03*
Y782167D03*
Y790041D03*
Y797915D03*
Y805790D03*
Y813664D03*
Y821538D03*
Y829412D03*
Y837286D03*
Y845160D03*
Y860908D03*
Y868782D03*
Y876656D03*
Y884530D03*
Y900278D03*
Y908152D03*
Y916026D03*
Y923900D03*
Y939648D03*
Y947522D03*
Y955396D03*
Y963270D03*
Y979018D03*
Y994766D03*
Y1002640D03*
Y1010514D03*
Y1026262D03*
X33267Y1061692D03*
Y1069566D03*
Y1077440D03*
Y1085314D03*
Y1101062D03*
Y1108936D03*
Y1116810D03*
Y1124684D03*
Y1140432D03*
Y1148306D03*
Y1156180D03*
Y1164055D03*
Y1179803D03*
Y1187677D03*
Y1195551D03*
Y1203425D03*
Y1219173D03*
Y1227047D03*
Y1234921D03*
Y1242795D03*
Y1258543D03*
Y1266417D03*
Y1274291D03*
Y1282165D03*
Y1290039D03*
Y1297913D03*
Y1305787D03*
Y1313661D03*
Y1321535D03*
Y1329409D03*
Y1337283D03*
Y1353031D03*
Y1368779D03*
Y1376653D03*
G54D39*
X287420Y162540D03*
X283086Y162675D03*
X285513Y337688D03*
X281074D03*
X289895D03*
X282776Y512341D03*
X278405D03*
X273938D03*
X269516D03*
X274514Y687192D03*
X270109D03*
X283340D03*
X278955D03*
X276686Y862488D03*
X272181Y862354D03*
X285788Y862237D03*
X281305D03*
X285666Y1031162D03*
X281124D03*
X290107D03*
X289082Y1206777D03*
X284194D03*
X279559D03*
X284240Y1389544D03*
X279518Y1389543D03*
X275052Y1389715D03*
X270579Y1389626D03*
X289675Y1558211D03*
X285054D03*
X274704Y1738196D03*
X279703Y1738398D03*
X284583Y1738465D03*
X289499Y1738735D03*
X287121Y1913327D03*
X282717D03*
X278262D03*
X273817D03*
X296523Y162585D03*
X291943Y162630D03*
X294506Y337688D03*
X294617Y1031162D03*
X293807Y1206777D03*
X298870Y1558211D03*
X294392D03*
G54D10*
X17735Y24953D03*
X27735D03*
X22735Y34953D03*
Y216976D03*
X27735Y206976D03*
X17735D03*
Y233811D03*
X27735D03*
X22735Y243811D03*
X27735Y415834D03*
X17735D03*
X22735Y425834D03*
Y1957291D03*
X27735Y1947291D03*
X17735D03*
X22735Y2061661D03*
X27735Y2051661D03*
X17735D03*
X47735Y24953D03*
X42735Y34953D03*
Y216976D03*
X47735Y206976D03*
X37735Y233811D03*
X47735D03*
X42735Y243811D03*
X47735Y415834D03*
X42735Y425834D03*
X32735D03*
X42735Y1957291D03*
X32735D03*
X47735Y1947291D03*
X42735Y2061661D03*
X32735D03*
X47735Y2051661D03*
X52735Y34953D03*
Y216976D03*
Y243811D03*
Y425834D03*
Y1957291D03*
Y2061661D03*
G54D22*
X23402Y1668874D03*
Y1718480D03*
Y1768087D03*
Y1817693D03*
X45056Y1668874D03*
Y1685410D03*
Y1701945D03*
Y1718480D03*
Y1735016D03*
Y1751551D03*
Y1768087D03*
Y1784622D03*
Y1817693D03*
Y1801158D03*
G54D33*
X166500Y111407D03*
X156430Y461714D03*
X153124Y1169037D03*
X154109Y1499221D03*
X152091Y1866003D03*
X175033Y261594D03*
X231339Y952454D03*
X225131Y1663167D03*
X267433Y624321D03*
X366169Y1360043D03*
Y1376210D03*
Y1367771D03*
G54D35*
X171524Y844722D03*
Y852165D03*
Y860201D03*
Y867720D03*
X169375Y1176256D03*
Y1190335D03*
Y1183740D03*
X169204Y1198253D03*
X170360Y1506440D03*
Y1513924D03*
Y1520519D03*
X170189Y1528437D03*
Y1535880D03*
Y1543916D03*
Y1551435D03*
X168342Y1880706D03*
Y1887301D03*
Y1873222D03*
X168171Y1902662D03*
Y1910698D03*
Y1895219D03*
Y1918217D03*
X179191Y822725D03*
Y830209D03*
X171695Y822725D03*
Y830209D03*
X179191Y836804D03*
X171695D03*
X179020Y844722D03*
Y852165D03*
Y860201D03*
Y867720D03*
X176871Y1176256D03*
Y1190335D03*
Y1183740D03*
X176700Y1198253D03*
X177856Y1506440D03*
Y1513924D03*
Y1520519D03*
X177685Y1528437D03*
Y1535880D03*
Y1543916D03*
Y1551435D03*
X175838Y1880706D03*
Y1887301D03*
Y1873222D03*
X175667Y1902662D03*
Y1910698D03*
Y1895219D03*
Y1918217D03*
X240955Y56999D03*
Y64483D03*
X240784Y78996D03*
X240955Y71078D03*
X240784Y94475D03*
Y101994D03*
Y86439D03*
X236537Y244995D03*
X244033D03*
X236537Y259074D03*
X236366Y266992D03*
Y274435D03*
X244033Y259074D03*
X243862Y266992D03*
Y274435D03*
X236537Y252479D03*
X244033D03*
X236366Y289990D03*
X243862D03*
X236366Y282471D03*
X243862D03*
X241371Y482381D03*
X241200Y490299D03*
X241371Y468302D03*
Y475786D03*
X241200Y513297D03*
Y497742D03*
Y505778D03*
X241382Y1670386D03*
X241211Y1699826D03*
X241382Y1677870D03*
X241211Y1692383D03*
X241382Y1684465D03*
X241211Y1715381D03*
Y1707862D03*
X248451Y56999D03*
Y64483D03*
X248280Y78996D03*
X248451Y71078D03*
X248280Y94475D03*
Y101994D03*
Y86439D03*
X248867Y482381D03*
X248696Y490299D03*
X248867Y468302D03*
Y475786D03*
X248696Y513297D03*
Y497742D03*
Y505778D03*
X254710Y608108D03*
Y601513D03*
Y594029D03*
X247214Y608108D03*
Y601513D03*
Y594029D03*
X254539Y631505D03*
Y623469D03*
Y616026D03*
X247043Y631505D03*
Y623469D03*
Y616026D03*
X254539Y639024D03*
X247043D03*
X255086Y959673D03*
Y973752D03*
Y967157D03*
X247590Y959673D03*
Y973752D03*
Y967157D03*
X254915Y981670D03*
Y997149D03*
Y989113D03*
X247419Y981670D03*
Y997149D03*
Y989113D03*
X254915Y1004668D03*
X247419D03*
X254978Y1215296D03*
X247482D03*
X254978Y1207777D03*
Y1199741D03*
X247482Y1207777D03*
Y1199741D03*
X248878Y1670386D03*
X248707Y1699826D03*
X248878Y1677870D03*
Y1684465D03*
X248707Y1692383D03*
Y1707862D03*
Y1715381D03*
X354391Y1329686D03*
Y1350706D03*
Y1360043D03*
Y1340201D03*
Y1376210D03*
Y1367771D03*
X366169Y1329686D03*
Y1350706D03*
Y1340201D03*
G54D16*
X17480Y599901D03*
Y627264D03*
Y1471949D03*
Y1499311D03*
G54D25*
X32735Y216976D03*
X37735Y206976D03*
Y415834D03*
Y1947291D03*
Y2051661D03*
G54D21*
X5491Y1603149D03*
X67499D03*
G54D41*
X307086Y1883071D03*
G54D19*
X20468Y696341D03*
Y984333D03*
X20472Y1054606D03*
Y1342598D03*
G54D12*
X12735Y59953D03*
Y181976D03*
Y268811D03*
Y390834D03*
Y1922291D03*
Y2026661D03*
X57735Y59953D03*
Y181976D03*
Y268811D03*
Y390834D03*
Y1922291D03*
Y2026661D03*
G54D40*
X307086Y308267D03*
G54D14*
X13995Y543701D03*
Y1587992D03*
X58995Y543701D03*
Y1587992D03*
G54D31*
X163385Y27205D03*
Y202205D03*
Y377205D03*
X163386Y552205D03*
Y727205D03*
X163385Y902205D03*
Y1077205D03*
Y1252205D03*
Y1427205D03*
Y1602205D03*
Y1777205D03*
Y1952205D03*
X373385Y32520D03*
Y207520D03*
Y382520D03*
X373386Y557520D03*
Y732520D03*
X373385Y907520D03*
Y1082520D03*
Y1257520D03*
Y1432520D03*
Y1607520D03*
Y1782520D03*
Y1957520D03*
G54D42*
X359842Y78780D03*
Y253780D03*
Y428779D03*
Y603779D03*
Y778780D03*
Y953780D03*
Y1128779D03*
Y1303780D03*
Y1478780D03*
Y1653780D03*
Y1828779D03*
Y2003780D03*
G54D20*
X15547Y723112D03*
X25389D03*
X15547Y746734D03*
X25389D03*
X7673Y734923D03*
Y766419D03*
X15547Y793979D03*
X25389D03*
X15547Y825475D03*
X25389D03*
X7673Y853034D03*
X15547Y864845D03*
X25389Y872719D03*
X7673Y884530D03*
X15547Y904215D03*
X25389Y912089D03*
X7673Y923900D03*
X15547Y943585D03*
X25389Y951459D03*
X7673Y963270D03*
X15547Y998703D03*
X7673Y1018388D03*
X25389Y1006577D03*
X15547Y1030199D03*
X25389D03*
X7677Y1069566D03*
X15551Y1089251D03*
X25393Y1073503D03*
Y1112873D03*
X7677Y1108936D03*
X15551Y1128622D03*
Y1167992D03*
X25393Y1152244D03*
X7677Y1148306D03*
X25393Y1191614D03*
X7677Y1187677D03*
X15551Y1207362D03*
X25393Y1230984D03*
X7677Y1227047D03*
X15551Y1246732D03*
X25393Y1262480D03*
Y1270354D03*
Y1286102D03*
X7677Y1266417D03*
Y1282165D03*
Y1313661D03*
X25393Y1317598D03*
X7677Y1360905D03*
X15551Y1356968D03*
X7677Y1376653D03*
X15551Y1364842D03*
X25393Y1372716D03*
X15551Y1388464D03*
X33263Y734923D03*
Y766419D03*
Y853034D03*
Y892404D03*
Y931774D03*
Y971144D03*
Y1018388D03*
X33267Y1093188D03*
Y1132558D03*
Y1171929D03*
Y1211299D03*
Y1250669D03*
Y1360905D03*
Y1384527D03*
G54D32*
X166500Y126110D03*
Y118626D03*
X166329Y140623D03*
X166500Y132705D03*
X166329Y148066D03*
Y156102D03*
Y163621D03*
X156430Y483012D03*
X156259Y490930D03*
X156430Y468933D03*
Y476417D03*
X156259Y513928D03*
Y498373D03*
Y506409D03*
X155444Y822725D03*
X162872D03*
Y830209D03*
X155444D03*
X162872Y836804D03*
X155444D03*
X162701Y844722D03*
X155273D03*
X162701Y852165D03*
X155273D03*
X162701Y860201D03*
X155273D03*
X162701Y867720D03*
X155273D03*
X153124Y1176256D03*
X160552D03*
Y1183740D03*
Y1190335D03*
X153124D03*
Y1183740D03*
X160552Y1169037D03*
X160381Y1198253D03*
X152953D03*
X161537Y1499221D03*
Y1506440D03*
X154109D03*
X153938Y1528437D03*
X154109Y1513924D03*
Y1520519D03*
X161537D03*
Y1513924D03*
X161366Y1528437D03*
X153938Y1535880D03*
Y1543916D03*
Y1551435D03*
X161366Y1535880D03*
Y1543916D03*
Y1551435D03*
X159519Y1866003D03*
X152091Y1880706D03*
Y1887301D03*
X159519D03*
Y1880706D03*
Y1873222D03*
X152091D03*
X151920Y1902662D03*
Y1910698D03*
X159348Y1902662D03*
Y1910698D03*
X151920Y1895219D03*
X159348D03*
X151920Y1918217D03*
X159348D03*
X173928Y126110D03*
Y118626D03*
Y111407D03*
X173757Y140623D03*
X173928Y132705D03*
X173757Y148066D03*
Y156102D03*
Y163621D03*
X175033Y268813D03*
Y282892D03*
X174862Y290810D03*
Y298253D03*
X175033Y276297D03*
X174862Y313808D03*
Y306289D03*
X227714Y237776D03*
Y244995D03*
Y259074D03*
X227543Y266992D03*
Y274435D03*
X227714Y252479D03*
X227543Y289990D03*
Y282471D03*
X232548Y461083D03*
Y482381D03*
X232377Y490299D03*
X232548Y468302D03*
Y475786D03*
X232377Y513297D03*
Y497742D03*
Y505778D03*
X230963Y608108D03*
X238391D03*
X230963Y601513D03*
X238391D03*
Y594029D03*
X230963D03*
X230792Y631505D03*
X238220D03*
X230792Y623469D03*
X238220D03*
X230792Y616026D03*
X238220D03*
X230792Y639024D03*
X238220D03*
X231339Y959673D03*
X238767D03*
Y967157D03*
Y973752D03*
X231339D03*
Y967157D03*
X238767Y952454D03*
X238596Y981670D03*
X231168D03*
X238596Y997149D03*
Y989113D03*
X231168Y997149D03*
Y989113D03*
X238596Y1004668D03*
X231168D03*
X238659Y1215296D03*
X231231D03*
X238659Y1207777D03*
Y1199741D03*
X231231Y1207777D03*
Y1199741D03*
X232559Y1663167D03*
Y1670386D03*
X225131D03*
X232559Y1684465D03*
Y1677870D03*
X232388Y1692383D03*
Y1699826D03*
X225131Y1684465D03*
Y1677870D03*
X224960Y1692383D03*
Y1699826D03*
X232388Y1707862D03*
Y1715381D03*
X224960Y1707862D03*
Y1715381D03*
X279044Y624627D03*
G54D36*
X173385Y32520D03*
Y21890D03*
X183385Y32520D03*
Y21890D03*
X193385Y32520D03*
Y21890D03*
X173385Y196890D03*
X183385D03*
X193385D03*
X173385Y207520D03*
X183385D03*
X193385D03*
X173385Y371890D03*
X183385D03*
X193385D03*
X173385Y382520D03*
X183385D03*
X193385D03*
X173386Y557520D03*
Y546890D03*
X183386Y557520D03*
Y546890D03*
X193386Y557520D03*
Y546890D03*
X173386Y732520D03*
Y721890D03*
X183386Y732520D03*
Y721890D03*
X193386Y732520D03*
Y721890D03*
X173385Y896890D03*
X183385D03*
X193385D03*
X173385Y907520D03*
X183385D03*
X193385D03*
X173385Y1071890D03*
X183385D03*
X193385D03*
X173385Y1082520D03*
X183385D03*
X193385D03*
X173385Y1257520D03*
Y1246890D03*
X183385Y1257520D03*
Y1246890D03*
X193385Y1257520D03*
Y1246890D03*
X173385Y1432520D03*
Y1421890D03*
X183385Y1432520D03*
Y1421890D03*
X193385Y1432520D03*
Y1421890D03*
X173385Y1596890D03*
X183385D03*
X193385D03*
X173385Y1607520D03*
X183385D03*
X193385D03*
X173385Y1771890D03*
X183385D03*
X193385D03*
X173385Y1782520D03*
X183385D03*
X193385D03*
X173385Y1957520D03*
Y1946890D03*
X183385Y1957520D03*
Y1946890D03*
X193385Y1957520D03*
Y1946890D03*
X203385Y32520D03*
Y21890D03*
X213385Y32520D03*
Y21890D03*
X203385Y196890D03*
X213385D03*
X203385Y207520D03*
X213385D03*
X203385Y371890D03*
X213385D03*
X203385Y382520D03*
X213385D03*
X203386Y557520D03*
Y546890D03*
X213386Y557520D03*
Y546890D03*
X203386Y732520D03*
Y721890D03*
X213386Y732520D03*
Y721890D03*
X203385Y896890D03*
X213385D03*
X203385Y907520D03*
X213385D03*
X203385Y1071890D03*
X213385D03*
X203385Y1082520D03*
X213385D03*
X203385Y1257520D03*
Y1246890D03*
X213385Y1257520D03*
Y1246890D03*
X203385Y1432520D03*
Y1421890D03*
X213385Y1432520D03*
Y1421890D03*
X203385Y1596890D03*
X213385D03*
X203385Y1607520D03*
X213385D03*
X203385Y1771890D03*
X213385D03*
X203385Y1782520D03*
X213385D03*
X203385Y1957520D03*
Y1946890D03*
X213385Y1957520D03*
Y1946890D03*
X223385Y32520D03*
Y21890D03*
X233385Y32520D03*
Y21890D03*
X243385Y32520D03*
Y21890D03*
X223385Y196890D03*
X233385D03*
X243385D03*
X223385Y207520D03*
X233385D03*
X243385D03*
X223385Y371890D03*
X233385D03*
X243385D03*
X223385Y382520D03*
X233385D03*
X243385D03*
X223386Y557520D03*
Y546890D03*
X233386Y557520D03*
Y546890D03*
X243386Y557520D03*
Y546890D03*
X223386Y732520D03*
Y721890D03*
X233386Y732520D03*
Y721890D03*
X243386Y732520D03*
Y721890D03*
X223385Y896890D03*
X233385D03*
X243385D03*
X223385Y907520D03*
X233385D03*
X243385D03*
X223385Y1071890D03*
X233385D03*
X243385D03*
X223385Y1082520D03*
X233385D03*
X243385D03*
X223385Y1257520D03*
Y1246890D03*
X233385Y1257520D03*
Y1246890D03*
X243385Y1257520D03*
Y1246890D03*
X223385Y1432520D03*
Y1421890D03*
X233385Y1432520D03*
Y1421890D03*
X243385Y1432520D03*
Y1421890D03*
X223385Y1596890D03*
X233385D03*
X243385D03*
X223385Y1607520D03*
X233385D03*
X243385D03*
X223385Y1771890D03*
X233385D03*
X243385D03*
X223385Y1782520D03*
X233385D03*
X243385D03*
X223385Y1957520D03*
Y1946890D03*
X233385Y1957520D03*
Y1946890D03*
X243385Y1957520D03*
Y1946890D03*
G54D28*
X65354Y114960D03*
Y464960D03*
Y814960D03*
Y1164960D03*
Y1514960D03*
Y1864960D03*
X307086Y127165D03*
Y477165D03*
Y827165D03*
Y1343504D03*
Y1693504D03*
X307087Y2043503D03*
G54D11*
X25219Y18752D03*
X3001Y52034D03*
Y100034D03*
Y150034D03*
Y200034D03*
Y250034D03*
Y300034D03*
Y350034D03*
Y400034D03*
Y450034D03*
Y500034D03*
Y550034D03*
X11677Y578766D03*
X3001Y600034D03*
Y650034D03*
Y700034D03*
Y750034D03*
Y800034D03*
Y850034D03*
Y900034D03*
Y950034D03*
Y1000034D03*
Y1050034D03*
Y1100034D03*
Y1150034D03*
Y1200034D03*
Y1250034D03*
Y1300034D03*
Y1350034D03*
Y1400034D03*
Y1450034D03*
Y1500034D03*
Y1550034D03*
X16484Y1552159D03*
X11085Y1552589D03*
X3006Y1594602D03*
X3012Y1610165D03*
X3001Y1650034D03*
Y1700034D03*
Y1750034D03*
Y1800034D03*
Y1850034D03*
Y1900034D03*
Y1950034D03*
Y2000034D03*
Y2050034D03*
X26833Y2067866D03*
X58750Y579653D03*
X63820Y579654D03*
X61888Y666012D03*
X57458Y1253378D03*
X54543Y1296513D03*
X63061Y1296312D03*
X67568Y1296654D03*
X54108Y1559138D03*
X75219Y18752D03*
X97417Y32853D03*
Y37438D03*
X97536Y376580D03*
X97457Y371909D03*
X97985Y391220D03*
X97643Y396024D03*
X98591Y720745D03*
X98564Y715937D03*
X97443Y739962D03*
X97534Y735248D03*
X98124Y745139D03*
X96904Y1067515D03*
X96948Y1092036D03*
X96949Y1087095D03*
X96774Y1072226D03*
X75475Y1315303D03*
X97403Y1424340D03*
X97825Y1419492D03*
X96993Y1443743D03*
X96996Y1438980D03*
X97465Y1447919D03*
X76833Y2067866D03*
X106335Y22580D03*
X108082Y38899D03*
X102646Y49461D03*
X104116Y82557D03*
X101990Y426104D03*
X101244Y774100D03*
X98652Y1096403D03*
X105684Y1125919D03*
X105455Y1472894D03*
X99103Y1765722D03*
X99068Y1760827D03*
X99047Y1785571D03*
X98873Y1780542D03*
X99294Y1789947D03*
X105669Y1815227D03*
X109991Y2083607D03*
X125219Y3002D03*
X162384Y56744D03*
X161742Y72497D03*
X162586Y68130D03*
X161377Y407575D03*
X161257Y420869D03*
X161826Y756757D03*
X161131Y774878D03*
X161644Y764231D03*
X164539Y1116135D03*
X162140Y1106853D03*
X163099Y1457084D03*
X162524Y1462651D03*
X162242Y1471380D03*
X163250Y1815631D03*
X162140Y1807740D03*
X159991Y2083607D03*
X175219Y3002D03*
X184284Y948331D03*
X184196Y967371D03*
X184632Y983423D03*
X184353Y1001556D03*
X184118Y1019280D03*
X188385Y1020810D03*
X209991Y2083607D03*
X225219Y3002D03*
X267627Y115559D03*
X259991Y2083607D03*
X275219Y3002D03*
X271547Y245353D03*
X276617Y241400D03*
X281193Y241624D03*
X286665Y417844D03*
X291002D03*
X281569Y421169D03*
X274991Y463099D03*
X285348Y595540D03*
X290984Y592215D03*
X273114Y770968D03*
X278184Y767643D03*
X282737D03*
X270070Y812192D03*
X275966Y944767D03*
X281194Y941442D03*
X285874D03*
X282958Y1119471D03*
X288188Y1116146D03*
X283808Y1293959D03*
X289210Y1290634D03*
X270234Y1467760D03*
X275521Y1464435D03*
X279990D03*
X284086Y1644883D03*
X289421Y1641558D03*
X281066Y1819569D03*
X291550Y1814846D03*
X286623Y1814400D03*
X299687Y63778D03*
X304151D03*
X308651D03*
X313089D03*
X294483Y67732D03*
X295509Y592215D03*
X292698Y1116146D03*
X294133Y1290634D03*
X313894Y1513883D03*
X294090Y1641558D03*
X293606Y1858668D03*
X314562Y1994087D03*
X309991Y2083607D03*
X325219Y3002D03*
X322005Y63778D03*
X317567D03*
X325796Y1162266D03*
X324803Y1990272D03*
X320045Y1990215D03*
X359991Y2083607D03*
X375219Y3002D03*
X402512Y17108D03*
Y67108D03*
Y117108D03*
Y167108D03*
Y217108D03*
Y267108D03*
Y317108D03*
Y367108D03*
Y417108D03*
Y467108D03*
Y517108D03*
Y567108D03*
Y617108D03*
Y667108D03*
Y717108D03*
Y767108D03*
Y817108D03*
Y867108D03*
Y917108D03*
Y967108D03*
Y1017108D03*
Y1067108D03*
Y1117108D03*
Y1167108D03*
Y1217108D03*
Y1267108D03*
Y1317108D03*
Y1367108D03*
Y1417108D03*
Y1467108D03*
Y1517108D03*
Y1567108D03*
Y1617108D03*
Y1667108D03*
Y1717108D03*
Y1767108D03*
Y1817108D03*
Y1867108D03*
Y1917108D03*
Y1967108D03*
Y2017108D03*
Y2067108D03*
G54D30*
X119920Y98071D03*
Y108071D03*
Y118071D03*
Y128071D03*
Y138071D03*
Y148071D03*
Y158071D03*
Y168071D03*
Y178071D03*
Y188071D03*
Y198071D03*
Y208071D03*
Y446102D03*
Y456102D03*
Y466102D03*
Y476102D03*
Y486102D03*
Y496102D03*
Y506102D03*
Y516102D03*
Y526102D03*
Y536102D03*
Y546102D03*
Y556102D03*
Y794134D03*
Y804134D03*
Y814134D03*
Y824134D03*
Y834134D03*
Y844134D03*
Y854134D03*
Y864134D03*
Y874134D03*
Y884134D03*
Y894134D03*
Y904134D03*
Y1142165D03*
Y1152165D03*
Y1162165D03*
Y1172165D03*
Y1182165D03*
Y1192165D03*
Y1202165D03*
Y1212165D03*
Y1222165D03*
Y1232165D03*
Y1242165D03*
Y1252165D03*
Y1490197D03*
Y1500197D03*
Y1510197D03*
Y1520197D03*
Y1530197D03*
Y1540197D03*
Y1550197D03*
Y1560197D03*
Y1570197D03*
Y1580197D03*
Y1590197D03*
Y1600197D03*
Y1838228D03*
Y1848228D03*
Y1858228D03*
Y1868228D03*
Y1878228D03*
Y1888228D03*
Y1898228D03*
Y1908228D03*
Y1918228D03*
Y1928228D03*
Y1938228D03*
Y1948228D03*
X139920Y98071D03*
Y128071D03*
Y118071D03*
Y108071D03*
Y148071D03*
Y138071D03*
Y178071D03*
Y168071D03*
Y158071D03*
Y198071D03*
Y188071D03*
Y208071D03*
Y466102D03*
Y456102D03*
Y446102D03*
Y486102D03*
Y476102D03*
Y516102D03*
Y506102D03*
Y496102D03*
Y536102D03*
Y526102D03*
Y556102D03*
Y546102D03*
Y804134D03*
Y794134D03*
Y824134D03*
Y814134D03*
Y854134D03*
Y844134D03*
Y834134D03*
Y874134D03*
Y864134D03*
Y904134D03*
Y894134D03*
Y884134D03*
Y1142165D03*
Y1162165D03*
Y1152165D03*
Y1192165D03*
Y1182165D03*
Y1172165D03*
Y1212165D03*
Y1202165D03*
Y1242165D03*
Y1232165D03*
Y1222165D03*
Y1252165D03*
Y1500197D03*
Y1490197D03*
Y1530197D03*
Y1520197D03*
Y1510197D03*
Y1550197D03*
Y1540197D03*
Y1580197D03*
Y1570197D03*
Y1560197D03*
Y1600197D03*
Y1590197D03*
Y1838228D03*
Y1868228D03*
Y1858228D03*
Y1848228D03*
Y1888228D03*
Y1878228D03*
Y1918228D03*
Y1908228D03*
Y1898228D03*
Y1938228D03*
Y1928228D03*
Y1948228D03*
G54D37*
X189762Y73105D03*
X190289Y152050D03*
X190357Y247568D03*
X190817Y331786D03*
X189761Y421732D03*
X190553Y506517D03*
X192888Y598130D03*
X190816Y681645D03*
X191846Y774526D03*
X191606Y856244D03*
X196311Y947202D03*
X195516Y1032544D03*
X191250Y1122856D03*
X191342Y1206233D03*
X191846Y1299104D03*
X190552Y1380966D03*
X189463Y1474162D03*
X191079Y1557277D03*
X192143Y1648177D03*
X191607Y1731351D03*
X191530Y1823227D03*
X190289Y1900420D03*
X192125Y1998730D03*
X191530Y2043388D03*
G54D23*
X23402Y1685410D03*
Y1701945D03*
Y1735016D03*
Y1751551D03*
Y1784622D03*
Y1801158D03*
G54D24*
X37735Y24953D03*
X32735Y34953D03*
Y243811D03*
G54D15*
X5491Y528544D03*
X67499D03*
%LPC*%
G75*
G54D43*
G01X-723776Y2987387D02*
Y-376795D01*
Y-489221D01*
X1782976D01*
Y-376795D01*
Y2987387D01*
X-723776D01*
G01X-4000Y-62500D02*
Y-137500D01*
X496000D01*
Y-62500D01*
X-4000D01*
G01X8000Y-127500D02*
Y-132500D01*
G01X6543Y-127500D02*
X9457D01*
G01X14367Y-132500D02*
X11833D01*
Y-127500D01*
X14367D01*
G01X13353Y-129917D02*
X11833D01*
G01X16933Y-127500D02*
Y-132500D01*
X19467D01*
G01X23300Y-132667D02*
X23173Y-132583D01*
Y-132417D01*
X23300Y-132333D01*
X23427Y-132417D01*
Y-132583D01*
X23300Y-132667D01*
G01Y-130417D02*
X23173Y-130333D01*
Y-130167D01*
X23300Y-130083D01*
X23427Y-130167D01*
Y-130333D01*
X23300Y-130417D01*
G01X28083Y-134167D02*
X27450Y-133333D01*
X27133Y-132500D01*
Y-129167D01*
X27450Y-128333D01*
X28083Y-127500D01*
G01X33500D02*
X32993Y-127667D01*
X32613Y-128083D01*
X32360Y-128583D01*
X32170Y-129250D01*
X32107Y-130000D01*
X32170Y-130750D01*
X32360Y-131417D01*
X32613Y-131917D01*
X32993Y-132333D01*
X33500Y-132500D01*
X34007Y-132333D01*
X34387Y-131917D01*
X34640Y-131417D01*
X34830Y-130750D01*
X34893Y-130000D01*
X34830Y-129250D01*
X34640Y-128583D01*
X34387Y-128083D01*
X34007Y-127667D01*
X33500Y-127500D01*
G01X37207Y-131500D02*
X37587Y-132083D01*
X38093Y-132417D01*
X38663Y-132500D01*
X39170Y-132417D01*
X39677Y-132000D01*
X39993Y-131500D01*
X40057Y-131000D01*
X39930Y-130417D01*
X39487Y-130000D01*
X39043Y-129833D01*
X38473D01*
G01X39043D02*
X39423Y-129583D01*
X39740Y-129167D01*
X39867Y-128667D01*
X39740Y-128167D01*
X39423Y-127750D01*
X38853Y-127500D01*
X38283Y-127583D01*
X37713Y-127917D01*
G01X44017Y-134167D02*
X44650Y-133333D01*
X44967Y-132500D01*
Y-129167D01*
X44650Y-128333D01*
X44017Y-127500D01*
G01X47407Y-131500D02*
X47787Y-132083D01*
X48293Y-132417D01*
X48863Y-132500D01*
X49370Y-132417D01*
X49877Y-132000D01*
X50193Y-131500D01*
X50257Y-131000D01*
X50130Y-130417D01*
X49687Y-130000D01*
X49243Y-129833D01*
X48673D01*
G01X49243D02*
X49623Y-129583D01*
X49940Y-129167D01*
X50067Y-128667D01*
X49940Y-128167D01*
X49623Y-127750D01*
X49053Y-127500D01*
X48483Y-127583D01*
X47913Y-127917D01*
G01X52697Y-128333D02*
X53077Y-127833D01*
X53520Y-127583D01*
X54027Y-127500D01*
X54660Y-127667D01*
X55103Y-128083D01*
X55230Y-128583D01*
X55167Y-129083D01*
X54913Y-129500D01*
X53647Y-130333D01*
X53077Y-130917D01*
X52697Y-131750D01*
X52570Y-132500D01*
X55230D01*
G01X58873D02*
X59000Y-131417D01*
X59190Y-130500D01*
X59443Y-129667D01*
X59760Y-128750D01*
X60267Y-127500D01*
X57733D01*
G01X63277Y-130833D02*
X64923D01*
G01X67997Y-128333D02*
X68377Y-127833D01*
X68820Y-127583D01*
X69327Y-127500D01*
X69960Y-127667D01*
X70403Y-128083D01*
X70530Y-128583D01*
X70467Y-129083D01*
X70213Y-129500D01*
X68947Y-130333D01*
X68377Y-130917D01*
X67997Y-131750D01*
X67870Y-132500D01*
X70530D01*
G01X72907Y-131500D02*
X73287Y-132083D01*
X73793Y-132417D01*
X74363Y-132500D01*
X74870Y-132417D01*
X75377Y-132000D01*
X75693Y-131500D01*
X75757Y-131000D01*
X75630Y-130417D01*
X75187Y-130000D01*
X74743Y-129833D01*
X74173D01*
G01X74743D02*
X75123Y-129583D01*
X75440Y-129167D01*
X75567Y-128667D01*
X75440Y-128167D01*
X75123Y-127750D01*
X74553Y-127500D01*
X73983Y-127583D01*
X73413Y-127917D01*
G01X80160Y-132500D02*
Y-127500D01*
X77817Y-131083D01*
X80983D01*
G01X83107Y-131750D02*
X83487Y-132167D01*
X83930Y-132417D01*
X84500Y-132500D01*
X85070Y-132333D01*
X85513Y-132000D01*
X85830Y-131417D01*
X85893Y-130750D01*
X85767Y-130083D01*
X85450Y-129667D01*
X85007Y-129333D01*
X84563Y-129250D01*
X84120Y-129333D01*
X83550Y-129667D01*
X83740Y-127500D01*
X85450D01*
G01X93497Y-132500D02*
Y-127500D01*
X95903D01*
G01X95017Y-129917D02*
X93497D01*
G01X98217Y-132500D02*
X99800Y-127500D01*
X101383Y-132500D01*
G01X100813Y-130750D02*
X98787D01*
G01X103570Y-132500D02*
X106230Y-127500D01*
G01X103570D02*
X106230Y-132500D01*
G01X110000Y-132667D02*
X109873Y-132583D01*
Y-132417D01*
X110000Y-132333D01*
X110127Y-132417D01*
Y-132583D01*
X110000Y-132667D01*
G01Y-130417D02*
X109873Y-130333D01*
Y-130167D01*
X110000Y-130083D01*
X110127Y-130167D01*
Y-130333D01*
X110000Y-130417D01*
G01X114783Y-134167D02*
X114150Y-133333D01*
X113833Y-132500D01*
Y-129167D01*
X114150Y-128333D01*
X114783Y-127500D01*
G01X120200D02*
X119693Y-127667D01*
X119313Y-128083D01*
X119060Y-128583D01*
X118870Y-129250D01*
X118807Y-130000D01*
X118870Y-130750D01*
X119060Y-131417D01*
X119313Y-131917D01*
X119693Y-132333D01*
X120200Y-132500D01*
X120707Y-132333D01*
X121087Y-131917D01*
X121340Y-131417D01*
X121530Y-130750D01*
X121593Y-130000D01*
X121530Y-129250D01*
X121340Y-128583D01*
X121087Y-128083D01*
X120707Y-127667D01*
X120200Y-127500D01*
G01X123907Y-131500D02*
X124287Y-132083D01*
X124793Y-132417D01*
X125363Y-132500D01*
X125870Y-132417D01*
X126377Y-132000D01*
X126693Y-131500D01*
X126757Y-131000D01*
X126630Y-130417D01*
X126187Y-130000D01*
X125743Y-129833D01*
X125173D01*
G01X125743D02*
X126123Y-129583D01*
X126440Y-129167D01*
X126567Y-128667D01*
X126440Y-128167D01*
X126123Y-127750D01*
X125553Y-127500D01*
X124983Y-127583D01*
X124413Y-127917D01*
G01X130717Y-134167D02*
X131350Y-133333D01*
X131667Y-132500D01*
Y-129167D01*
X131350Y-128333D01*
X130717Y-127500D01*
G01X134107Y-131500D02*
X134487Y-132083D01*
X134993Y-132417D01*
X135563Y-132500D01*
X136070Y-132417D01*
X136577Y-132000D01*
X136893Y-131500D01*
X136957Y-131000D01*
X136830Y-130417D01*
X136387Y-130000D01*
X135943Y-129833D01*
X135373D01*
G01X135943D02*
X136323Y-129583D01*
X136640Y-129167D01*
X136767Y-128667D01*
X136640Y-128167D01*
X136323Y-127750D01*
X135753Y-127500D01*
X135183Y-127583D01*
X134613Y-127917D01*
G01X139523Y-131917D02*
X139967Y-132333D01*
X140473Y-132500D01*
X140980Y-132333D01*
X141423Y-131833D01*
X141740Y-131083D01*
X141867Y-130333D01*
Y-129417D01*
X141740Y-128667D01*
X141423Y-128000D01*
X141043Y-127667D01*
X140600Y-127500D01*
X140093Y-127667D01*
X139713Y-128000D01*
X139460Y-128500D01*
X139333Y-129167D01*
X139460Y-129750D01*
X139777Y-130333D01*
X140157Y-130667D01*
X140600Y-130750D01*
X141107Y-130583D01*
X141487Y-130167D01*
X141867Y-129417D01*
G01X145573Y-132500D02*
X145700Y-131417D01*
X145890Y-130500D01*
X146143Y-129667D01*
X146460Y-128750D01*
X146967Y-127500D01*
X144433D01*
G01X149977Y-130833D02*
X151623D01*
G01X154507Y-131500D02*
X154887Y-132083D01*
X155393Y-132417D01*
X155963Y-132500D01*
X156470Y-132417D01*
X156977Y-132000D01*
X157293Y-131500D01*
X157357Y-131000D01*
X157230Y-130417D01*
X156787Y-130000D01*
X156343Y-129833D01*
X155773D01*
G01X156343D02*
X156723Y-129583D01*
X157040Y-129167D01*
X157167Y-128667D01*
X157040Y-128167D01*
X156723Y-127750D01*
X156153Y-127500D01*
X155583Y-127583D01*
X155013Y-127917D01*
G01X159797Y-130417D02*
X160240Y-129833D01*
X160620Y-129500D01*
X161127Y-129333D01*
X161570Y-129500D01*
X161887Y-129833D01*
X162140Y-130333D01*
X162203Y-130917D01*
X162140Y-131417D01*
X161887Y-131917D01*
X161507Y-132333D01*
X161063Y-132500D01*
X160557Y-132333D01*
X160113Y-131833D01*
X159860Y-131083D01*
X159797Y-130250D01*
X159923Y-129167D01*
X160113Y-128583D01*
X160430Y-128000D01*
X160873Y-127583D01*
X161317Y-127500D01*
X161760Y-127667D01*
X162077Y-128083D01*
G01X166100Y-132500D02*
Y-127500D01*
X165340Y-128500D01*
G01Y-132500D02*
X166860D01*
G01X171960D02*
Y-127500D01*
X169617Y-131083D01*
X172783D01*
G01X191000Y-62500D02*
Y-137500D01*
G01Y-112500D02*
X294000D01*
Y-87500D01*
G01X191000D02*
X294000D01*
G01X301507Y-122500D02*
Y-117500D01*
X302773D01*
X303280Y-117750D01*
X303660Y-118083D01*
X303977Y-118583D01*
X304230Y-119167D01*
X304293Y-120000D01*
X304230Y-120833D01*
X303977Y-121417D01*
X303660Y-121917D01*
X303280Y-122250D01*
X302773Y-122500D01*
X301507D01*
G01X306417D02*
X308000Y-117500D01*
X309583Y-122500D01*
G01X309013Y-120750D02*
X306987D01*
G01X313100Y-117500D02*
Y-122500D01*
G01X311643Y-117500D02*
X314557D01*
G01X319467Y-122500D02*
X316933D01*
Y-117500D01*
X319467D01*
G01X318453Y-119917D02*
X316933D01*
G01X323300Y-122667D02*
X323173Y-122583D01*
Y-122417D01*
X323300Y-122333D01*
X323427Y-122417D01*
Y-122583D01*
X323300Y-122667D01*
G01Y-120417D02*
X323173Y-120333D01*
Y-120167D01*
X323300Y-120083D01*
X323427Y-120167D01*
Y-120333D01*
X323300Y-120417D01*
G01X296000Y-62500D02*
Y-137500D01*
G01X294000Y-62500D02*
Y-137500D01*
G01X301633Y-97500D02*
Y-92500D01*
X303153D01*
X303660Y-92750D01*
X304040Y-93333D01*
X304167Y-94000D01*
X304040Y-94667D01*
X303723Y-95167D01*
X303153Y-95417D01*
X301633D01*
G01X306860Y-97667D02*
X309140Y-92500D01*
G01X311643Y-97500D02*
Y-92500D01*
X314557Y-97500D01*
Y-92500D01*
G01X318200Y-97667D02*
X318073Y-97583D01*
Y-97417D01*
X318200Y-97333D01*
X318327Y-97417D01*
Y-97583D01*
X318200Y-97667D01*
G01Y-95417D02*
X318073Y-95333D01*
Y-95167D01*
X318200Y-95083D01*
X318327Y-95167D01*
Y-95333D01*
X318200Y-95417D01*
G01X296000Y-112500D02*
X496000D01*
G01X301633Y-72500D02*
Y-67500D01*
X303153D01*
X303660Y-67750D01*
X304040Y-68333D01*
X304167Y-69000D01*
X304040Y-69667D01*
X303723Y-70167D01*
X303153Y-70417D01*
X301633D01*
G01X306733Y-72500D02*
Y-67500D01*
X308317D01*
X308823Y-67750D01*
X309140Y-68083D01*
X309267Y-68750D01*
X309140Y-69417D01*
X308760Y-69833D01*
X308317Y-70083D01*
X306733D01*
G01X308317D02*
X309267Y-72500D01*
G01X313100D02*
X312593Y-72417D01*
X312150Y-72083D01*
X311770Y-71583D01*
X311517Y-71000D01*
X311390Y-70333D01*
Y-69667D01*
X311517Y-69000D01*
X311770Y-68417D01*
X312150Y-67917D01*
X312593Y-67583D01*
X313100Y-67500D01*
X313607Y-67583D01*
X314050Y-67917D01*
X314430Y-68417D01*
X314683Y-69000D01*
X314810Y-69667D01*
Y-70333D01*
X314683Y-71000D01*
X314430Y-71583D01*
X314050Y-72083D01*
X313607Y-72417D01*
X313100Y-72500D01*
G01X316933Y-71500D02*
X317250Y-72000D01*
X317630Y-72333D01*
X318073Y-72500D01*
X318580Y-72333D01*
X318960Y-72000D01*
X319340Y-71500D01*
X319467Y-70833D01*
Y-67500D01*
G01X324567Y-72500D02*
X322033D01*
Y-67500D01*
X324567D01*
G01X323553Y-69917D02*
X322033D01*
G01X329793Y-67917D02*
X329413Y-67667D01*
X328970Y-67500D01*
X328463D01*
X327893Y-67750D01*
X327450Y-68167D01*
X327133Y-68667D01*
X326880Y-69500D01*
X326817Y-70250D01*
X326943Y-71000D01*
X327133Y-71500D01*
X327513Y-72000D01*
X327957Y-72333D01*
X328400Y-72500D01*
X328843D01*
X329287Y-72333D01*
X329667Y-72083D01*
X329983Y-71750D01*
G01X333500Y-67500D02*
Y-72500D01*
G01X332043Y-67500D02*
X334957D01*
G01X338600Y-72667D02*
X338473Y-72583D01*
Y-72417D01*
X338600Y-72333D01*
X338727Y-72417D01*
Y-72583D01*
X338600Y-72667D01*
G01Y-70417D02*
X338473Y-70333D01*
Y-70167D01*
X338600Y-70083D01*
X338727Y-70167D01*
Y-70333D01*
X338600Y-70417D01*
G01X296000Y-87500D02*
X496000D01*
G01X411000Y-112500D02*
Y-137500D01*
G01X416633Y-122500D02*
Y-117500D01*
X418217D01*
X418723Y-117750D01*
X419040Y-118083D01*
X419167Y-118750D01*
X419040Y-119417D01*
X418660Y-119833D01*
X418217Y-120083D01*
X416633D01*
G01X418217D02*
X419167Y-122500D01*
G01X424267D02*
X421733D01*
Y-117500D01*
X424267D01*
G01X423253Y-119917D02*
X421733D01*
G01X426517Y-117500D02*
X428100Y-122500D01*
X429683Y-117500D01*
G01X433200Y-122667D02*
X433073Y-122583D01*
Y-122417D01*
X433200Y-122333D01*
X433327Y-122417D01*
Y-122583D01*
X433200Y-122667D01*
G01Y-120417D02*
X433073Y-120333D01*
Y-120167D01*
X433200Y-120083D01*
X433327Y-120167D01*
Y-120333D01*
X433200Y-120417D01*
G01X460000Y-112500D02*
Y-137500D01*
G01X-723776Y2987387D02*
Y-376795D01*
Y-489221D01*
X1782976D01*
Y-376795D01*
Y2987387D01*
X-723776D01*
G01X6705Y-124160D02*
X7332Y-124685D01*
X8037Y-125000D01*
X8663D01*
X9290Y-124685D01*
X9760Y-124160D01*
X9995Y-123425D01*
X9838Y-122690D01*
X9447Y-122060D01*
X8742Y-121640D01*
X7802Y-121430D01*
X7253Y-121010D01*
X7018Y-120275D01*
X7175Y-119540D01*
X7567Y-119015D01*
X8115Y-118700D01*
X8663D01*
X9212Y-118910D01*
X9682Y-119435D01*
G01X13005Y-125000D02*
Y-118700D01*
G01X16295D02*
Y-125000D01*
G01Y-121850D02*
X13005D01*
G01X20010Y-118700D02*
X21890D01*
G01X20950D02*
Y-125000D01*
G01X20010D02*
X21890D01*
G01X28817D02*
X25683D01*
Y-118700D01*
X28817D01*
G01X27563Y-121745D02*
X25683D01*
G01X31748Y-125000D02*
Y-118700D01*
X35352Y-125000D01*
Y-118700D01*
G01X39693Y-126155D02*
X40007Y-124790D01*
G01X46150Y-118700D02*
Y-125000D01*
G01X44348Y-118700D02*
X47952D01*
G01X50492Y-125000D02*
X52450Y-118700D01*
X54408Y-125000D01*
G01X53703Y-122795D02*
X51197D01*
G01X57810Y-118700D02*
X59690D01*
G01X58750D02*
Y-125000D01*
G01X57810D02*
X59690D01*
G01X62700Y-118700D02*
X63797Y-125000D01*
X65050Y-118700D01*
X66303Y-125000D01*
X67400Y-118700D01*
G01X69392Y-125000D02*
X71350Y-118700D01*
X73308Y-125000D01*
G01X72603Y-122795D02*
X70097D01*
G01X75848Y-125000D02*
Y-118700D01*
X79452Y-125000D01*
Y-118700D01*
G01X88683Y-125000D02*
Y-118700D01*
X90642D01*
X91268Y-119015D01*
X91660Y-119435D01*
X91817Y-120275D01*
X91660Y-121115D01*
X91190Y-121640D01*
X90642Y-121955D01*
X88683D01*
G01X90642D02*
X91817Y-125000D01*
G01X96550Y-125210D02*
X96393Y-125105D01*
Y-124895D01*
X96550Y-124790D01*
X96707Y-124895D01*
Y-125105D01*
X96550Y-125210D01*
G01X102850Y-125000D02*
X102223Y-124895D01*
X101675Y-124475D01*
X101205Y-123845D01*
X100892Y-123110D01*
X100735Y-122270D01*
Y-121430D01*
X100892Y-120590D01*
X101205Y-119855D01*
X101675Y-119225D01*
X102223Y-118805D01*
X102850Y-118700D01*
X103477Y-118805D01*
X104025Y-119225D01*
X104495Y-119855D01*
X104808Y-120590D01*
X104965Y-121430D01*
Y-122270D01*
X104808Y-123110D01*
X104495Y-123845D01*
X104025Y-124475D01*
X103477Y-124895D01*
X102850Y-125000D01*
G01X109150Y-125210D02*
X108993Y-125105D01*
Y-124895D01*
X109150Y-124790D01*
X109307Y-124895D01*
Y-125105D01*
X109150Y-125210D01*
G01X117173Y-119225D02*
X116703Y-118910D01*
X116155Y-118700D01*
X115528D01*
X114823Y-119015D01*
X114275Y-119540D01*
X113883Y-120170D01*
X113570Y-121220D01*
X113492Y-122165D01*
X113648Y-123110D01*
X113883Y-123740D01*
X114353Y-124370D01*
X114902Y-124790D01*
X115450Y-125000D01*
X115998D01*
X116547Y-124790D01*
X117017Y-124475D01*
X117408Y-124055D01*
G01X121750Y-125210D02*
X121593Y-125105D01*
Y-124895D01*
X121750Y-124790D01*
X121907Y-124895D01*
Y-125105D01*
X121750Y-125210D01*
G01X6627Y-115000D02*
Y-108700D01*
G01X9603D02*
X6627Y-112585D01*
G01X10073Y-115000D02*
X7958Y-110800D01*
G01X12927Y-108700D02*
Y-113215D01*
X13240Y-114160D01*
X13867Y-114790D01*
X14650Y-115000D01*
X15433Y-114790D01*
X16060Y-114160D01*
X16373Y-113215D01*
Y-108700D01*
G01X22517Y-115000D02*
X19383D01*
Y-108700D01*
X22517D01*
G01X21263Y-111745D02*
X19383D01*
G01X26310Y-108700D02*
X28190D01*
G01X27250D02*
Y-115000D01*
G01X26310D02*
X28190D01*
G01X38205Y-114160D02*
X38832Y-114685D01*
X39537Y-115000D01*
X40163D01*
X40790Y-114685D01*
X41260Y-114160D01*
X41495Y-113425D01*
X41338Y-112690D01*
X40947Y-112060D01*
X40242Y-111640D01*
X39302Y-111430D01*
X38753Y-111010D01*
X38518Y-110275D01*
X38675Y-109540D01*
X39067Y-109015D01*
X39615Y-108700D01*
X40163D01*
X40712Y-108910D01*
X41182Y-109435D01*
G01X44505Y-115000D02*
Y-108700D01*
G01X47795D02*
Y-115000D01*
G01Y-111850D02*
X44505D01*
G01X50492Y-115000D02*
X52450Y-108700D01*
X54408Y-115000D01*
G01X53703Y-112795D02*
X51197D01*
G01X56948Y-115000D02*
Y-108700D01*
X60552Y-115000D01*
Y-108700D01*
G01X69705Y-115000D02*
Y-108700D01*
G01X72995D02*
Y-115000D01*
G01Y-111850D02*
X69705D01*
G01X76005Y-114160D02*
X76632Y-114685D01*
X77337Y-115000D01*
X77963D01*
X78590Y-114685D01*
X79060Y-114160D01*
X79295Y-113425D01*
X79138Y-112690D01*
X78747Y-112060D01*
X78042Y-111640D01*
X77102Y-111430D01*
X76553Y-111010D01*
X76318Y-110275D01*
X76475Y-109540D01*
X76867Y-109015D01*
X77415Y-108700D01*
X77963D01*
X78512Y-108910D01*
X78982Y-109435D01*
G01X83010Y-108700D02*
X84890D01*
G01X83950D02*
Y-115000D01*
G01X83010D02*
X84890D01*
G01X88292D02*
X90250Y-108700D01*
X92208Y-115000D01*
G01X91503Y-112795D02*
X88997D01*
G01X94748Y-115000D02*
Y-108700D01*
X98352Y-115000D01*
Y-108700D01*
G01X103320Y-111850D02*
X104887D01*
Y-113740D01*
X104417Y-114370D01*
X103868Y-114790D01*
X103085Y-115000D01*
X102302Y-114790D01*
X101753Y-114370D01*
X101283Y-113740D01*
X100970Y-113005D01*
X100813Y-112165D01*
Y-111430D01*
X100970Y-110800D01*
X101283Y-110065D01*
X101753Y-109435D01*
X102223Y-109015D01*
X102850Y-108700D01*
X103398D01*
X104025Y-108910D01*
X104495Y-109330D01*
G01X108993Y-116155D02*
X109307Y-114790D01*
G01X115450Y-108700D02*
Y-115000D01*
G01X113648Y-108700D02*
X117252D01*
G01X119792Y-115000D02*
X121750Y-108700D01*
X123708Y-115000D01*
G01X123003Y-112795D02*
X120497D01*
G01X128050Y-115000D02*
X127423Y-114895D01*
X126875Y-114475D01*
X126405Y-113845D01*
X126092Y-113110D01*
X125935Y-112270D01*
Y-111430D01*
X126092Y-110590D01*
X126405Y-109855D01*
X126875Y-109225D01*
X127423Y-108805D01*
X128050Y-108700D01*
X128677Y-108805D01*
X129225Y-109225D01*
X129695Y-109855D01*
X130008Y-110590D01*
X130165Y-111430D01*
Y-112270D01*
X130008Y-113110D01*
X129695Y-113845D01*
X129225Y-114475D01*
X128677Y-114895D01*
X128050Y-115000D01*
G01X140650D02*
Y-112165D01*
X139083Y-108700D01*
G01X142217D02*
X140650Y-112165D01*
G01X145227Y-108700D02*
Y-113215D01*
X145540Y-114160D01*
X146167Y-114790D01*
X146950Y-115000D01*
X147733Y-114790D01*
X148360Y-114160D01*
X148673Y-113215D01*
Y-108700D01*
G01X151292Y-115000D02*
X153250Y-108700D01*
X155208Y-115000D01*
G01X154503Y-112795D02*
X151997D01*
G01X157748Y-115000D02*
Y-108700D01*
X161352Y-115000D01*
Y-108700D01*
G01X30650Y-92300D02*
X28130Y-91883D01*
X25925Y-90217D01*
X24035Y-87717D01*
X22775Y-84800D01*
X22145Y-81467D01*
Y-78133D01*
X22775Y-74800D01*
X24035Y-71883D01*
X25925Y-69384D01*
X28130Y-67717D01*
X30650Y-67300D01*
X33170Y-67717D01*
X35375Y-69384D01*
X37265Y-71883D01*
X38525Y-74800D01*
X39155Y-78133D01*
Y-81467D01*
X38525Y-84800D01*
X37265Y-87717D01*
X35375Y-90217D01*
X33170Y-91883D01*
X30650Y-92300D01*
G01X33170Y-85633D02*
X36950Y-92300D01*
G01X50495Y-75634D02*
Y-87300D01*
X51755Y-90217D01*
X53645Y-91883D01*
X55850Y-92300D01*
X58055Y-91883D01*
X59945Y-90217D01*
X61205Y-87300D01*
G01Y-92300D02*
Y-75634D01*
G01X86720Y-92300D02*
Y-75634D01*
G01Y-78550D02*
X85460Y-76884D01*
X83570Y-76050D01*
X81365Y-75634D01*
X79160Y-76467D01*
X77270Y-78133D01*
X76010Y-80634D01*
X75380Y-83967D01*
X76010Y-87300D01*
X77270Y-89801D01*
X79160Y-91467D01*
X81365Y-92300D01*
X83570Y-91883D01*
X85460Y-90634D01*
X86720Y-88967D01*
G01X100895Y-92300D02*
Y-75634D01*
G01Y-79800D02*
X102155Y-77717D01*
X104045Y-76050D01*
X106565Y-75634D01*
X108770Y-76050D01*
X110660Y-77717D01*
X111605Y-80634D01*
Y-92300D01*
G01X131450Y-67300D02*
Y-92300D01*
G01X127040Y-75634D02*
X135860D01*
G01X162320Y-92300D02*
Y-75634D01*
G01Y-78550D02*
X161060Y-76884D01*
X159170Y-76050D01*
X156965Y-75634D01*
X154760Y-76467D01*
X152870Y-78133D01*
X151610Y-80634D01*
X150980Y-83967D01*
X151610Y-87300D01*
X152870Y-89801D01*
X154760Y-91467D01*
X156965Y-92300D01*
X159170Y-91883D01*
X161060Y-90634D01*
X162320Y-88967D01*
G01X6548Y-105000D02*
Y-98700D01*
X10152Y-105000D01*
Y-98700D01*
G01X14650Y-105000D02*
X14023Y-104895D01*
X13475Y-104475D01*
X13005Y-103845D01*
X12692Y-103110D01*
X12535Y-102270D01*
Y-101430D01*
X12692Y-100590D01*
X13005Y-99855D01*
X13475Y-99225D01*
X14023Y-98805D01*
X14650Y-98700D01*
X15277Y-98805D01*
X15825Y-99225D01*
X16295Y-99855D01*
X16608Y-100590D01*
X16765Y-101430D01*
Y-102270D01*
X16608Y-103110D01*
X16295Y-103845D01*
X15825Y-104475D01*
X15277Y-104895D01*
X14650Y-105000D01*
G01X20950Y-105210D02*
X20793Y-105105D01*
Y-104895D01*
X20950Y-104790D01*
X21107Y-104895D01*
Y-105105D01*
X20950Y-105210D01*
G01X27250Y-105000D02*
Y-98700D01*
X26310Y-99960D01*
G01Y-105000D02*
X28190D01*
G01X33550D02*
X34098Y-104895D01*
X34725Y-104580D01*
X35117Y-104055D01*
X35273Y-103320D01*
X35117Y-102585D01*
X34647Y-101955D01*
X33942Y-101640D01*
X33158D01*
X32688Y-101430D01*
X32297Y-100905D01*
X32140Y-100170D01*
X32375Y-99435D01*
X32923Y-98910D01*
X33550Y-98700D01*
X34177Y-98910D01*
X34725Y-99435D01*
X34960Y-100170D01*
X34803Y-100905D01*
X34412Y-101430D01*
X33942Y-101640D01*
X33158D01*
X32453Y-101955D01*
X31983Y-102585D01*
X31827Y-103320D01*
X31983Y-104055D01*
X32375Y-104580D01*
X33002Y-104895D01*
X33550Y-105000D01*
G01X39850D02*
X40398Y-104895D01*
X41025Y-104580D01*
X41417Y-104055D01*
X41573Y-103320D01*
X41417Y-102585D01*
X40947Y-101955D01*
X40242Y-101640D01*
X39458D01*
X38988Y-101430D01*
X38597Y-100905D01*
X38440Y-100170D01*
X38675Y-99435D01*
X39223Y-98910D01*
X39850Y-98700D01*
X40477Y-98910D01*
X41025Y-99435D01*
X41260Y-100170D01*
X41103Y-100905D01*
X40712Y-101430D01*
X40242Y-101640D01*
X39458D01*
X38753Y-101955D01*
X38283Y-102585D01*
X38127Y-103320D01*
X38283Y-104055D01*
X38675Y-104580D01*
X39302Y-104895D01*
X39850Y-105000D01*
G01X45993Y-106155D02*
X46307Y-104790D01*
G01X50100Y-98700D02*
X51197Y-105000D01*
X52450Y-98700D01*
X53703Y-105000D01*
X54800Y-98700D01*
G01X60317Y-105000D02*
X57183D01*
Y-98700D01*
X60317D01*
G01X59063Y-101745D02*
X57183D01*
G01X63248Y-105000D02*
Y-98700D01*
X66852Y-105000D01*
Y-98700D01*
G01X76005Y-105000D02*
Y-98700D01*
G01X79295D02*
Y-105000D01*
G01Y-101850D02*
X76005D01*
G01X81600Y-98700D02*
X82697Y-105000D01*
X83950Y-98700D01*
X85203Y-105000D01*
X86300Y-98700D01*
G01X88292Y-105000D02*
X90250Y-98700D01*
X92208Y-105000D01*
G01X91503Y-102795D02*
X88997D01*
G01X101362Y-99750D02*
X101832Y-99120D01*
X102380Y-98805D01*
X103007Y-98700D01*
X103790Y-98910D01*
X104338Y-99435D01*
X104495Y-100065D01*
X104417Y-100695D01*
X104103Y-101220D01*
X102537Y-102270D01*
X101832Y-103005D01*
X101362Y-104055D01*
X101205Y-105000D01*
X104495D01*
G01X107348D02*
Y-98700D01*
X110952Y-105000D01*
Y-98700D01*
G01X113727Y-105000D02*
Y-98700D01*
X115293D01*
X115920Y-99015D01*
X116390Y-99435D01*
X116782Y-100065D01*
X117095Y-100800D01*
X117173Y-101850D01*
X117095Y-102900D01*
X116782Y-103635D01*
X116390Y-104265D01*
X115920Y-104685D01*
X115293Y-105000D01*
X113727D01*
G01X126483D02*
Y-98700D01*
X128442D01*
X129068Y-99015D01*
X129460Y-99435D01*
X129617Y-100275D01*
X129460Y-101115D01*
X128990Y-101640D01*
X128442Y-101955D01*
X126483D01*
G01X128442D02*
X129617Y-105000D01*
G01X132627D02*
Y-98700D01*
X134193D01*
X134820Y-99015D01*
X135290Y-99435D01*
X135682Y-100065D01*
X135995Y-100800D01*
X136073Y-101850D01*
X135995Y-102900D01*
X135682Y-103635D01*
X135290Y-104265D01*
X134820Y-104685D01*
X134193Y-105000D01*
X132627D01*
G01X140650Y-105210D02*
X140493Y-105105D01*
Y-104895D01*
X140650Y-104790D01*
X140807Y-104895D01*
Y-105105D01*
X140650Y-105210D01*
G01X202000Y-72000D02*
Y-80000D01*
X206000D01*
G01X213800D02*
Y-74667D01*
G01Y-75600D02*
X213400Y-75067D01*
X212800Y-74800D01*
X212100Y-74667D01*
X211400Y-74933D01*
X210800Y-75467D01*
X210400Y-76267D01*
X210200Y-77333D01*
X210400Y-78400D01*
X210800Y-79200D01*
X211400Y-79733D01*
X212100Y-80000D01*
X212800Y-79867D01*
X213400Y-79467D01*
X213800Y-78934D01*
G01X217900Y-82400D02*
X218500Y-82667D01*
X219300Y-82400D01*
X219800Y-81867D01*
X220200Y-81200D01*
X220800Y-79067D01*
X222100Y-74667D01*
G01X218900D02*
X220800Y-79067D01*
G01X226500Y-76400D02*
X229700D01*
X229400Y-75467D01*
X228900Y-74933D01*
X228200Y-74667D01*
X227500Y-74800D01*
X226900Y-75200D01*
X226500Y-76133D01*
X226300Y-76934D01*
Y-77733D01*
X226500Y-78533D01*
X227000Y-79333D01*
X227600Y-79867D01*
X228300Y-80000D01*
X229000Y-79733D01*
X229700Y-78934D01*
G01X234600Y-80000D02*
Y-74667D01*
G01Y-75733D02*
X235100Y-75200D01*
X235600Y-74800D01*
X236300Y-74667D01*
X236800Y-74800D01*
X237400Y-75200D01*
G01X223400Y-128934D02*
X224200Y-129600D01*
X225100Y-130000D01*
X225900D01*
X226700Y-129600D01*
X227300Y-128934D01*
X227600Y-128000D01*
X227400Y-127067D01*
X226900Y-126267D01*
X226000Y-125733D01*
X224800Y-125467D01*
X224100Y-124933D01*
X223800Y-124000D01*
X224000Y-123067D01*
X224500Y-122400D01*
X225200Y-122000D01*
X225900D01*
X226600Y-122267D01*
X227200Y-122933D01*
G01X235300Y-130000D02*
Y-124667D01*
G01Y-125600D02*
X234900Y-125067D01*
X234300Y-124800D01*
X233600Y-124667D01*
X232900Y-124933D01*
X232300Y-125467D01*
X231900Y-126267D01*
X231700Y-127333D01*
X231900Y-128400D01*
X232300Y-129200D01*
X232900Y-129733D01*
X233600Y-130000D01*
X234300Y-129867D01*
X234900Y-129467D01*
X235300Y-128934D01*
G01X239800Y-130000D02*
Y-124667D01*
G01Y-126000D02*
X240200Y-125333D01*
X240800Y-124800D01*
X241600Y-124667D01*
X242300Y-124800D01*
X242900Y-125333D01*
X243200Y-126267D01*
Y-130000D01*
G01X251300Y-122000D02*
Y-130000D01*
G01Y-128800D02*
X250900Y-129467D01*
X250300Y-129867D01*
X249600Y-130000D01*
X248800Y-129733D01*
X248200Y-129067D01*
X247800Y-128267D01*
X247700Y-127333D01*
X247800Y-126400D01*
X248200Y-125600D01*
X248800Y-124933D01*
X249600Y-124667D01*
X250300Y-124800D01*
X250800Y-125067D01*
X251300Y-125600D01*
G01X255400Y-132400D02*
X256000Y-132667D01*
X256800Y-132400D01*
X257300Y-131867D01*
X257700Y-131200D01*
X258300Y-129067D01*
X259600Y-124667D01*
G01X256400D02*
X258300Y-129067D01*
G01X233600Y-101000D02*
X235600D01*
Y-103400D01*
X235000Y-104200D01*
X234300Y-104733D01*
X233300Y-105000D01*
X232300Y-104733D01*
X231600Y-104200D01*
X231000Y-103400D01*
X230600Y-102467D01*
X230400Y-101400D01*
Y-100467D01*
X230600Y-99667D01*
X231000Y-98733D01*
X231600Y-97933D01*
X232200Y-97400D01*
X233000Y-97000D01*
X233700D01*
X234500Y-97267D01*
X235100Y-97800D01*
G01X238700Y-105000D02*
Y-97000D01*
X243300Y-105000D01*
Y-97000D01*
G01X246800Y-105000D02*
Y-97000D01*
X248800D01*
X249600Y-97400D01*
X250200Y-97933D01*
X250700Y-98733D01*
X251100Y-99667D01*
X251200Y-101000D01*
X251100Y-102333D01*
X250700Y-103267D01*
X250200Y-104067D01*
X249600Y-104600D01*
X248800Y-105000D01*
X246800D01*
G01X257000D02*
Y-97000D01*
X255800Y-98600D01*
G01Y-105000D02*
X258200D01*
G01X255300Y-80000D02*
X255500Y-78267D01*
X255800Y-76800D01*
X256200Y-75467D01*
X256700Y-74000D01*
X257500Y-72000D01*
X253500D01*
G01X328600Y-123333D02*
X329200Y-122533D01*
X329900Y-122133D01*
X330700Y-122000D01*
X331700Y-122267D01*
X332400Y-122933D01*
X332600Y-123733D01*
X332500Y-124534D01*
X332100Y-125200D01*
X330100Y-126533D01*
X329200Y-127467D01*
X328600Y-128800D01*
X328400Y-130000D01*
X332600D01*
G01X338500Y-122000D02*
X337700Y-122267D01*
X337100Y-122933D01*
X336700Y-123733D01*
X336400Y-124800D01*
X336300Y-126000D01*
X336400Y-127200D01*
X336700Y-128267D01*
X337100Y-129067D01*
X337700Y-129733D01*
X338500Y-130000D01*
X339300Y-129733D01*
X339900Y-129067D01*
X340300Y-128267D01*
X340600Y-127200D01*
X340700Y-126000D01*
X340600Y-124800D01*
X340300Y-123733D01*
X339900Y-122933D01*
X339300Y-122267D01*
X338500Y-122000D01*
G01X346500Y-130000D02*
Y-122000D01*
X345300Y-123600D01*
G01Y-130000D02*
X347700D01*
G01X352600Y-123333D02*
X353200Y-122533D01*
X353900Y-122133D01*
X354700Y-122000D01*
X355700Y-122267D01*
X356400Y-122933D01*
X356600Y-123733D01*
X356500Y-124534D01*
X356100Y-125200D01*
X354100Y-126533D01*
X353200Y-127467D01*
X352600Y-128800D01*
X352400Y-130000D01*
X356600D01*
G01X360700Y-130267D02*
X364300Y-122000D01*
G01X370500D02*
X369700Y-122267D01*
X369100Y-122933D01*
X368700Y-123733D01*
X368400Y-124800D01*
X368300Y-126000D01*
X368400Y-127200D01*
X368700Y-128267D01*
X369100Y-129067D01*
X369700Y-129733D01*
X370500Y-130000D01*
X371300Y-129733D01*
X371900Y-129067D01*
X372300Y-128267D01*
X372600Y-127200D01*
X372700Y-126000D01*
X372600Y-124800D01*
X372300Y-123733D01*
X371900Y-122933D01*
X371300Y-122267D01*
X370500Y-122000D01*
G01X376800Y-129067D02*
X377500Y-129733D01*
X378300Y-130000D01*
X379100Y-129733D01*
X379800Y-128934D01*
X380300Y-127733D01*
X380500Y-126533D01*
Y-125067D01*
X380300Y-123867D01*
X379800Y-122800D01*
X379200Y-122267D01*
X378500Y-122000D01*
X377700Y-122267D01*
X377100Y-122800D01*
X376700Y-123600D01*
X376500Y-124667D01*
X376700Y-125600D01*
X377200Y-126533D01*
X377800Y-127067D01*
X378500Y-127200D01*
X379300Y-126934D01*
X379900Y-126267D01*
X380500Y-125067D01*
G01X384700Y-130267D02*
X388300Y-122000D01*
G01X392600Y-123333D02*
X393200Y-122533D01*
X393900Y-122133D01*
X394700Y-122000D01*
X395700Y-122267D01*
X396400Y-122933D01*
X396600Y-123733D01*
X396500Y-124534D01*
X396100Y-125200D01*
X394100Y-126533D01*
X393200Y-127467D01*
X392600Y-128800D01*
X392400Y-130000D01*
X396600D01*
G01X402500D02*
X403200Y-129867D01*
X404000Y-129467D01*
X404500Y-128800D01*
X404700Y-127867D01*
X404500Y-126934D01*
X403900Y-126133D01*
X403000Y-125733D01*
X402000D01*
X401400Y-125467D01*
X400900Y-124800D01*
X400700Y-123867D01*
X401000Y-122933D01*
X401700Y-122267D01*
X402500Y-122000D01*
X403300Y-122267D01*
X404000Y-122933D01*
X404300Y-123867D01*
X404100Y-124800D01*
X403600Y-125467D01*
X403000Y-125733D01*
X402000D01*
X401100Y-126133D01*
X400500Y-126934D01*
X400300Y-127867D01*
X400500Y-128800D01*
X401000Y-129467D01*
X401800Y-129867D01*
X402500Y-130000D01*
G01X328300Y-105000D02*
Y-97000D01*
X330300D01*
X331100Y-97400D01*
X331700Y-97933D01*
X332200Y-98733D01*
X332600Y-99667D01*
X332700Y-101000D01*
X332600Y-102333D01*
X332200Y-103267D01*
X331700Y-104067D01*
X331100Y-104600D01*
X330300Y-105000D01*
X328300D01*
G01X336000D02*
X338500Y-97000D01*
X341000Y-105000D01*
G01X340100Y-102200D02*
X336900D01*
G01X346500Y-97000D02*
X345700Y-97267D01*
X345100Y-97933D01*
X344700Y-98733D01*
X344400Y-99800D01*
X344300Y-101000D01*
X344400Y-102200D01*
X344700Y-103267D01*
X345100Y-104067D01*
X345700Y-104733D01*
X346500Y-105000D01*
X347300Y-104733D01*
X347900Y-104067D01*
X348300Y-103267D01*
X348600Y-102200D01*
X348700Y-101000D01*
X348600Y-99800D01*
X348300Y-98733D01*
X347900Y-97933D01*
X347300Y-97267D01*
X346500Y-97000D01*
G01X354500D02*
Y-105000D01*
G01X352200Y-97000D02*
X356800D01*
G01X360600Y-101667D02*
X361300Y-100733D01*
X361900Y-100200D01*
X362700Y-99933D01*
X363400Y-100200D01*
X363900Y-100733D01*
X364300Y-101533D01*
X364400Y-102467D01*
X364300Y-103267D01*
X363900Y-104067D01*
X363300Y-104733D01*
X362600Y-105000D01*
X361800Y-104733D01*
X361100Y-103934D01*
X360700Y-102733D01*
X360600Y-101400D01*
X360800Y-99667D01*
X361100Y-98733D01*
X361600Y-97800D01*
X362300Y-97133D01*
X363000Y-97000D01*
X363700Y-97267D01*
X364200Y-97933D01*
G01X367900Y-105000D02*
Y-97000D01*
X370500Y-103667D01*
X373100Y-97000D01*
Y-105000D01*
G01X378500Y-97000D02*
Y-105000D01*
G01X376200Y-97000D02*
X380800D01*
G01X387300Y-100733D02*
X387700Y-100333D01*
X388000Y-99667D01*
X388200Y-98733D01*
X388000Y-97933D01*
X387600Y-97400D01*
X386900Y-97000D01*
X384200D01*
Y-105000D01*
X387500D01*
X388200Y-104467D01*
X388600Y-103667D01*
X388800Y-102733D01*
X388600Y-101800D01*
X388000Y-101000D01*
X387300Y-100733D01*
X384200D01*
G01X394500Y-105000D02*
X395200Y-104867D01*
X396000Y-104467D01*
X396500Y-103800D01*
X396700Y-102867D01*
X396500Y-101934D01*
X395900Y-101133D01*
X395000Y-100733D01*
X394000D01*
X393400Y-100467D01*
X392900Y-99800D01*
X392700Y-98867D01*
X393000Y-97933D01*
X393700Y-97267D01*
X394500Y-97000D01*
X395300Y-97267D01*
X396000Y-97933D01*
X396300Y-98867D01*
X396100Y-99800D01*
X395600Y-100467D01*
X395000Y-100733D01*
X394000D01*
X393100Y-101133D01*
X392500Y-101934D01*
X392300Y-102867D01*
X392500Y-103800D01*
X393000Y-104467D01*
X393800Y-104867D01*
X394500Y-105000D01*
G01X400300D02*
Y-97000D01*
X402300D01*
X403100Y-97400D01*
X403700Y-97933D01*
X404200Y-98733D01*
X404600Y-99667D01*
X404700Y-101000D01*
X404600Y-102333D01*
X404200Y-103267D01*
X403700Y-104067D01*
X403100Y-104600D01*
X402300Y-105000D01*
X400300D01*
G01X410500Y-97000D02*
X409700Y-97267D01*
X409100Y-97933D01*
X408700Y-98733D01*
X408400Y-99800D01*
X408300Y-101000D01*
X408400Y-102200D01*
X408700Y-103267D01*
X409100Y-104067D01*
X409700Y-104733D01*
X410500Y-105000D01*
X411300Y-104733D01*
X411900Y-104067D01*
X412300Y-103267D01*
X412600Y-102200D01*
X412700Y-101000D01*
X412600Y-99800D01*
X412300Y-98733D01*
X411900Y-97933D01*
X411300Y-97267D01*
X410500Y-97000D01*
G01X350500Y-72000D02*
Y-80000D01*
G01X348200Y-72000D02*
X352800D01*
G01X356600Y-76667D02*
X357300Y-75733D01*
X357900Y-75200D01*
X358700Y-74933D01*
X359400Y-75200D01*
X359900Y-75733D01*
X360300Y-76533D01*
X360400Y-77467D01*
X360300Y-78267D01*
X359900Y-79067D01*
X359300Y-79733D01*
X358600Y-80000D01*
X357800Y-79733D01*
X357100Y-78934D01*
X356700Y-77733D01*
X356600Y-76400D01*
X356800Y-74667D01*
X357100Y-73733D01*
X357600Y-72800D01*
X358300Y-72133D01*
X359000Y-72000D01*
X359700Y-72267D01*
X360200Y-72933D01*
G01X363900Y-80000D02*
Y-72000D01*
X366500Y-78667D01*
X369100Y-72000D01*
Y-80000D01*
G01X371500Y-82667D02*
X377500D01*
G01X380500Y-80000D02*
Y-72000D01*
X382900D01*
X383700Y-72400D01*
X384300Y-73333D01*
X384500Y-74400D01*
X384300Y-75467D01*
X383800Y-76267D01*
X382900Y-76667D01*
X380500D01*
G01X388300Y-80000D02*
Y-72000D01*
X390300D01*
X391100Y-72400D01*
X391700Y-72933D01*
X392200Y-73733D01*
X392600Y-74667D01*
X392700Y-76000D01*
X392600Y-77333D01*
X392200Y-78267D01*
X391700Y-79067D01*
X391100Y-79600D01*
X390300Y-80000D01*
X388300D01*
G01X399300Y-75733D02*
X399700Y-75333D01*
X400000Y-74667D01*
X400200Y-73733D01*
X400000Y-72933D01*
X399600Y-72400D01*
X398900Y-72000D01*
X396200D01*
Y-80000D01*
X399500D01*
X400200Y-79467D01*
X400600Y-78667D01*
X400800Y-77733D01*
X400600Y-76800D01*
X400000Y-76000D01*
X399300Y-75733D01*
X396200D01*
G01X403500Y-82667D02*
X409500D01*
G01X412300Y-80000D02*
Y-72000D01*
X414300D01*
X415100Y-72400D01*
X415700Y-72933D01*
X416200Y-73733D01*
X416600Y-74667D01*
X416700Y-76000D01*
X416600Y-77333D01*
X416200Y-78267D01*
X415700Y-79067D01*
X415100Y-79600D01*
X414300Y-80000D01*
X412300D01*
G01X419500Y-82667D02*
X425500D01*
G01X431300Y-75733D02*
X431700Y-75333D01*
X432000Y-74667D01*
X432200Y-73733D01*
X432000Y-72933D01*
X431600Y-72400D01*
X430900Y-72000D01*
X428200D01*
Y-80000D01*
X431500D01*
X432200Y-79467D01*
X432600Y-78667D01*
X432800Y-77733D01*
X432600Y-76800D01*
X432000Y-76000D01*
X431300Y-75733D01*
X428200D01*
G01X436300Y-80000D02*
Y-72000D01*
X438300D01*
X439100Y-72400D01*
X439700Y-72933D01*
X440200Y-73733D01*
X440600Y-74667D01*
X440700Y-76000D01*
X440600Y-77333D01*
X440200Y-78267D01*
X439700Y-79067D01*
X439100Y-79600D01*
X438300Y-80000D01*
X436300D01*
G01X443300Y-130000D02*
Y-122000D01*
X445300D01*
X446100Y-122400D01*
X446700Y-122933D01*
X447200Y-123733D01*
X447600Y-124667D01*
X447700Y-126000D01*
X447600Y-127333D01*
X447200Y-128267D01*
X446700Y-129067D01*
X446100Y-129600D01*
X445300Y-130000D01*
X443300D01*
G01X473000D02*
Y-122000D01*
X471800Y-123600D01*
G01Y-130000D02*
X474200D01*
G01X478800Y-128800D02*
X479400Y-129467D01*
X480100Y-129867D01*
X481000Y-130000D01*
X481900Y-129733D01*
X482600Y-129200D01*
X483100Y-128267D01*
X483200Y-127200D01*
X483000Y-126133D01*
X482500Y-125467D01*
X481800Y-124933D01*
X481100Y-124800D01*
X480400Y-124933D01*
X479500Y-125467D01*
X479800Y-122000D01*
X482500D01*
M02*
